5
5
4
4
3
3
2
2
1
1
D D
C C
B B
A A
CHASSIS MANAGEMENT BOARD 
DVT 
PCB P/N:DAT6MTH3AD0 
Date : 2012/10/23 
PCB Rev : D 
Title 
Size Document Number Rev
Date: Sheet 
of 
Cover 1A
Chassis Manager Assembly V1 
Cloud Server Infrastructure Engineering
C
1 85Monday, January 27, 2014 
Title 
Size Document Number Rev
Date: Sheet 
of 
Cover 1A
Chassis Manager Assembly V1 
Cloud Server Infrastructure Engineering
C
1 85Monday, January 27, 2014 
Title 
Size Document Number Rev
Date: Sheet 
of 
Cover 1A
Chassis Manager Assembly V1 
Cloud Server Infrastructure Engineering
C
1 85Monday, January 27, 2014 



5
5
4
4
3
3
2
2
1
1
D D
C C
B B
A A
Cover page 
POWER ON SEQUENCE NODE1 USB CONTROLLER 
BLANK 
NODE1 82574 LAN (1) 
NODE1 82574 LAN (2) 
BLANK 
SIO 
RS232 SIGNAL DIVIDER 
SATA HDD/VGA 
LAN TRANSFORMER 
RS232 DRIVER/RECEIVER 
USB 
CMC 
ADT7470 
SMC & CPLD 
GOLD FINGER 
FLTER 1 
FLTER 2 
FLTER 3 
FLTER 4 
HOT PLUG 
NODE1 CPLD (1) 
NODE1 CPLD (2) 
NODE1 POWER_BUTTON 
LEVEL SHIT 
P5V_STB &P3V3_STB 
P1V05_SUS & P1V0_NODE1 
P1V5_SUS & P1V8_SUS 
P1V8_STB & P1V538_BMC 
P1V26_BMC 
P3V3_SUS 
P5V & P3V3 
P1V8 & P1V05 
P1V5 
PV_VDDR & PV_VTT_DDR 
VCCP_CPU 
SCREW, HOLE, MISC 
SET2DIL 
BLANK 
BLANK 
NODE1 HDD CONTROLLER (1) 
NODE1 HDD CONTROLLER (2) 
CPLD CONNECTION 
STACKUP 
BLANK 
CLOCK GEN 
NODE1 CPU DDR3 INTERFACE 
NODE1 CPU PCIE INTERFACE 
NODE1 CPU GPIO LPC UART 
NODE1 CPU NTB INTERFACE 
NODE1 CPU SMB SOC 
NODE1 CPU MANAGEMENT RESET 
NODE1 CPU POWER RAILS 
NODE1 CPU GNDS 
NODE1 CPU STRAPPING 
NODE1 CPU SPI&80 PORT&TPM 
NODE1 CPU DECOUPLING 
BLANK 
NODE1 CPU TEMPERATURE ADC 
NODE1 SO-DIMM DIMM 
BLANK 
PCIE_SWITCH 
BLANK 
NODE1 AST1300_DDRIII & I2C 
NODE1 AST1300_DDRIII MEMORY 
NODE1 AST1300 SPI_UART_MAC 
BLANK 
NODE1 AST1300_GPIO_JTAG_MIS 
NODE1 AST1300_POWER 
NODE1 AST1300_HW STRAPPING 
BLANK 
BLANK 
BLANK 
BLANK 
BLANK 
BLANK 
BLANK 
CLOCK BLOCK DIAGRAM 
I2C BLOCK DIAGRAM 
PWRGD/RST DIAGRAM 
BLANK 
POWER TOPOLOGY 
Page# DESCRIPTION Page# Page# DESCRIPTION DESCRIPTION 
3
4
5
7
9
10 
12 
18 
19 
20 
21 
23 
24 
25 
28 
29 
30 
31 
32 
33 
34 
35 
36 
37 
38 
39 
40 
41 
42 
43 
15 
14 
13 
11 
8
6
2
1
27 
26 
22 
17 
16 
71 
57 
58 
52 
53 
54 
55 
56 
47 
48 
49 
50 
51 
68 
69 
70 
44 
45 
46 
63 
64 
65 
66 
67 
59 
60 
61 
62 
82 
81 
80 
79 
77 
76 
75 
74 
78 
73 
72 
85 
84 
83 
SYSTEM BLOCK DIAGRAM 
INDEX 
Page# DESCRIPTION 
Title 
Size Document Number Rev
Date: Sheet 
of 
Index 1A
Chassis Manager Assembly V1 
Cloud Server Infrastructure Engineering
C
2 85Monday, January 27, 2014 
Title 
Size Document Number Rev
Date: Sheet 
of 
Index 1A
Chassis Manager Assembly V1 
Cloud Server Infrastructure Engineering
C
2 85Monday, January 27, 2014 
Title 
Size Document Number Rev
Date: Sheet 
of 
Index 1A
Chassis Manager Assembly V1 
Cloud Server Infrastructure Engineering
C
2 85Monday, January 27, 2014 



5
5
4
4
3
3
2
2
1
1
D D
C C
B B
A A
Title 
Size Document Number Rev
Date: Sheet 
of 
System Block Diagram 1A
Chassis Manager Assembly V1 
Cloud Server Infrastructure Engineering
C
3 85Monday, January 27, 2014 
Title 
Size Document Number Rev
Date: Sheet 
of 
System Block Diagram 1A
Chassis Manager Assembly V1 
Cloud Server Infrastructure Engineering
C
3 85Monday, January 27, 2014 
Title 
Size Document Number Rev
Date: Sheet 
of 
System Block Diagram 1A
Chassis Manager Assembly V1 
Cloud Server Infrastructure Engineering
C
3 85Monday, January 27, 2014 



5
5
4
4
3
3
2
2
1
1
D D
C C
B B
A A
POWER-UP SCHEME 
System Power Up/Down Sequence 
P1V8_STB_NODE1 BMC VR 
Dotted line indicates that battery is not present 
t1b 5ms >
FP_PWR_BTN CPLD BOARD 
P3V3_STB_NODE1 VR 
CPLD 
BMC 
NIC 
SOURCE DESTINATION SIGNAL 
Battery CPU P3V3_RTC_NODE1 
t1 5ms >
>t2 0ms 
Brd logic CPU RST_CPU_NODE1_RTCRESET_L 
FM_CPLD_NODE1_PWR_BTN_CPU CPU CPLD 
P5V_STB_NODE1 MOS VR, MISC 
PV_VDDR_NODE1 
VR PV_VTT_DDR_NODE1 
P1V05_SUS_NODE1 
P1V5_SUS_NODE1 
P3V3_SUS_NODE1 
P1V8_SUS_NODE1 
FM_CPLD_NODE1_CPU_RSMRST_L 
P3V3_NODE1 
P1V05_NODE1 
P1V8_NODE1 
P1V5_NODE1 
P1V0_NODE1 
PV_VCCP_NODE1 CPU VR 
FM_CPLD_NODE1_SYS_PG CPU CPLD 
CLOCK SYS Clocks CPLD 
SUSCLOCK CPLD CPU 
PWROK is released when all the VRs PWRGD 
have been  received 
FM_CPLD_NODE1_CPU_RESET_L CPU CPLD 
FM_CPU_NODE1_RSTRDY_L CPLD CPU 
FM_CPU_NODE1_RSTWARN CPU CPLD 
FM_CPU_NODE1_SLPMODE CPLD CPU 
P12V_AUX Board PDB 
MOS P5V_NODE1 
USB 
SATA 
VGA 
MOS CPU 
MOS CPU 
CPU 
DIMM 
CPU 
VR 
VR 
VR 
CPU 
DIMM 
CPU 
DIMM 
CPU CPLD 
VR ALL 
MOS 
CPU 
SATA 
CPU 
CLK GEN MOS 
VR 
CPU 
CLK GEN 
XDP 
LDO PCIE SW 
P1V538_BMC_NODE1 BMC LDO 
BMC P1V26_BMC_NODE1 LDO 
SATA 
Title 
Size Document Number Rev 
Date: Sheet 
of 
Power On Sequence 1A 
Chassis Manager Assembly V1 
Cloud Server Infrastructure Engineering 
Custom 
4 85 Monday, January 27, 2014 
Title 
Size Document Number Rev 
Date: Sheet 
of 
Power On Sequence 1A 
Chassis Manager Assembly V1 
Cloud Server Infrastructure Engineering 
Custom 
4 85 Monday, January 27, 2014 
Title 
Size Document Number Rev 
Date: Sheet 
of 
Power On Sequence 1A 
Chassis Manager Assembly V1 
Cloud Server Infrastructure Engineering 
Custom 
4 85 Monday, January 27, 2014 



5
5
4
4
3
3
2
2
1
1
D D
C C
B B
A A
Title 
Size Document Number Rev
Date: Sheet 
of 
Stackup 1A
Chassis Manager Assembly V1 
Cloud Server Infrastructure Engineering
C
5 85Monday, January 27, 2014 
Title 
Size Document Number Rev
Date: Sheet 
of 
Stackup 1A
Chassis Manager Assembly V1 
Cloud Server Infrastructure Engineering
C
5 85Monday, January 27, 2014 
Title 
Size Document Number Rev
Date: Sheet 
of 
Stackup 1A
Chassis Manager Assembly V1 
Cloud Server Infrastructure Engineering
C
5 85Monday, January 27, 2014 



5
5
4
4
3
3
2
2
1
1
D D
C C
B B
A A
Title 
Size Document Number Rev
Date: Sheet 
of 
CPLD Connection 1A
Chassis Manager Assembly V1 
Cloud Server Infrastructure Engineering
C
6 85Monday, January 27, 2014 
Title 
Size Document Number Rev
Date: Sheet 
of 
CPLD Connection 1A
Chassis Manager Assembly V1 
Cloud Server Infrastructure Engineering
C
6 85Monday, January 27, 2014 
Title 
Size Document Number Rev
Date: Sheet 
of 
CPLD Connection 1A
Chassis Manager Assembly V1 
Cloud Server Infrastructure Engineering
C
6 85Monday, January 27, 2014 



5
5
4
4
3
3
2
2
1
1
D D
C C
B B
A A
9VRS4339BKLFT 
CPU0 
CPU1 
CRYSTAL 
25MHZ 
S1200 CPU 
DDR3_CLK 
HPLL_CLK 
RP0_CLKIN 
CLK_14M_IN 
SUS_CLK 
LPC_CLK0 
LPC_CLK1 
DDR3_CLK[1:0] 
100MHZ_DDR3 
100MHZ_CPU 
100MHZ_PCIE 
SRC2 
14M 14MHZ_REF_CLK 
CRYSTAL 
32.768KHZ 
33MHZ_LPC_BMC 
33MHZ_LPC_TPM 
666MHZ_DDR 
DIMM 
BMC AST1300 
PCIE CLK 
CLK-IN 
M-CLK 100MHZ_PCIE_BMC SRC7 
OSC 
48MHZ 
48MHZ_BMC 
DRAM 
82574L 
XTAL CRYSTAL 
25MHZ 
PCIE CLK SRC4 CLK_100M_NIC2 
SATA 88SE9130 
PCIE CLK 
OSC 
CLK_100M_SATA SATA 
25MHZ 25MHZ_SATA 
USB PD720201A 
PCIE CLK 
XTAL 
CLK_100M_USB SRC6 
USB48 
0.8V 
3.3V 
DDR_Vcc (1.5V or 1.35V) 
DDR3 1.5V 
CRYSTAL 
24MHZ 
82574L 
XTAL CRYSTAL 
25MHZ 
PCIE CLK SRC3 CLK_100M_NIC1 
TPM 
LPC_CPU_NODE1_CLKOUT1 
CPLD 32.768KHZ_CPLD_CLK OSC 
32.768KHZ 
PI7C9X20303SLFDE 
PCIE CLK SRC5/DOT96 
SIO 
LPC_CPU_NODE1_CLKOUT0 
CLK_48M_SIO SIO 
CLK_33M_PORT80 PORT80 PCI 
Title 
Size Document Number Rev
Date: Sheet 
of 
Clock Block Diagram 1A
Chassis Manager Assembly V1 
Cloud Server Infrastructure Engineering
C
7 85Monday, January 27, 2014 
Title 
Size Document Number Rev
Date: Sheet 
of 
Clock Block Diagram 1A
Chassis Manager Assembly V1 
Cloud Server Infrastructure Engineering
C
7 85Monday, January 27, 2014 
Title 
Size Document Number Rev
Date: Sheet 
of 
Clock Block Diagram 1A
Chassis Manager Assembly V1 
Cloud Server Infrastructure Engineering
C
7 85Monday, January 27, 2014 



5
5
4
4
3
3
2
2
1
1
D D
C C
B B
A A
Title 
Size Document Number Rev
Date: Sheet 
of 
I2C Block Diagram 1A
Chassis Manager Assembly V1 
Cloud Server Infrastructure Engineering
C
8 85Monday, January 27, 2014 
Title 
Size Document Number Rev
Date: Sheet 
of 
I2C Block Diagram 1A
Chassis Manager Assembly V1 
Cloud Server Infrastructure Engineering
C
8 85Monday, January 27, 2014 
Title 
Size Document Number Rev
Date: Sheet 
of 
I2C Block Diagram 1A
Chassis Manager Assembly V1 
Cloud Server Infrastructure Engineering
C
8 85Monday, January 27, 2014 



5
5
4
4
3
3
2
2
1
1
D D
C C
B B
A A
FM_CPLD_NODE1_SYS_PG 
AON7212 
(P1V8_SUS_NODE1) 
FM_CPLD_NODE1_P1V8_SUS_EN 
TPS54326 
(P5V_STB_NODE1) 
FM_CPLD_NODE1_CPU_RSMRST_L 
P12V_AUX 
CPU 
EPM240F100C5N 
TPS54326RGTR 
(P1V8_STB_NODE1) 
FM_CPLD_NODE1_P1V8_STB_EN 
PWRGD_NODE1_P1V8_STB_PG 
RT9018B-25GQW 
(P1V538_BMC_NODE1) 
FM_CPLD_NODE1_P1V538_BMC_EN 
PWRGD_NODE1_P1V538_BMC_PG 
RT9018B-18GQW 
(P1V26_BMC_NODE1) 
FM_CPLD_NODE1_P1V26_STB_EN 
PWRGD_NODE1_P1V26_STB_PG 
TPS51518RUKR 
(PV_VDDR_NODE1) 
FM_CPLD_NODE1_PVDDR_STB_EN 
PWRGD_NODE1_PVDDR_STB_PG 
TPS51200 
(PV_VTT_DDR_NODE1) 
FM_CPLD_NODE1_PVTT_DDR_EN 
PWRGD_NODE1_PVTT_DDR_PG 
RT9018B-25GQW 
(P1V05_SUS_NODE1) 
FM_CPLD_NODE1_P1V05_SUS_EN 
PWRGD_NODE1_P1V05_SUS_PG 
RT9018B-25GQW 
(P1V5_SUS_NODE1) 
FM_CPLD_NODE1_P1V5_SUS_EN 
PWRGD_NODE1_P1V05_SUS_PG 
FM_CPLD_NODE1_PWR_BTN_L 
PWR_BTN_NODE1_L 
FM_CPLD_NODE1_CPU_RESET_L 
AON7212 
(P5V_NODE1) 
FM_CPLD_NODE1_P5V_EN 
P5V_STB_NODE1_EN 
TPS54326RGTR 
(P3V3_STB_NODE1) 
PWRGD_NODE1_P5V_STB_PG 
MAX809SEUR+ 
AON7212 
(P3V3_SUS_NODE1) 
FM_CPLD_NODE1_P3V3_SUS_EN 
FM_CPU_NODE1_RSTRDY_L 
FM_CPU_NODE1_RSTWARN 
FM_CPU_NODE1_SLPMODE 
FM_CPLD_NODE1_P1V5_EN 
FM_CPLD_NODE1_P1V0_EN 
PWRGD_NODE1_PVCCP_PG 
RT8167BGQW 
(PV_VCCP_NODE1) 
FM_CPLD_NODE1_PVCCP_EN 
AON7212 
(P1V8_NODE1) 
FM_CPLD_NODE1_P1V8_EN 
AON7212 
(P1V5_NODE1) 
TPS54326RGTR 
(P3V3_NODE1) 
FM_CPLD_NODE1_P3V3_EN 
PWRGD_NODE1_P3V3_PG 
PWRGD_NODE1_P3V3_STB_PG 
RST_CPU_NODE1_SRTCRST_L 
PWRGD_NODE1_P12V_PG 
RT9018B-25GQW 
(P1V0_NODE1) 
PWRGD_NODE1_P1V0_NODE1 
TPS51219RTER 
(P1V05_NODE1) 
FM_CPLD_NODE1_P1V05_EN 
PWRGD_N1_P1V05_PG 
Title 
Size Document Number Rev
Date: Sheet 
of 
Power Good / Reset Tree 1A
Chassis Manager Assembly V1 
Cloud Server Infrastructure Engineering
C
9 85Monday, January 27, 2014 
Title 
Size Document Number Rev
Date: Sheet 
of 
Power Good / Reset Tree 1A
Chassis Manager Assembly V1 
Cloud Server Infrastructure Engineering
C
9 85Monday, January 27, 2014 
Title 
Size Document Number Rev
Date: Sheet 
of 
Power Good / Reset Tree 1A
Chassis Manager Assembly V1 
Cloud Server Infrastructure Engineering
C
9 85Monday, January 27, 2014 



5
5
4
4
3
3
2
2
1
1
D D
C C
B B
A A
Title 
Size Document Number Rev
Date: Sheet 
of 
Blank 1A
Chassis Manager Assembly V1 
Cloud Server Infrastructure Engineering
C
10 85Monday, January 27, 2014 
Title 
Size Document Number Rev
Date: Sheet 
of 
Blank 1A
Chassis Manager Assembly V1 
Cloud Server Infrastructure Engineering
C
10 85Monday, January 27, 2014 
Title 
Size Document Number Rev
Date: Sheet 
of 
Blank 1A
Chassis Manager Assembly V1 
Cloud Server Infrastructure Engineering
C
10 85Monday, January 27, 2014 



5
5
4
4
3
3
2
2
1
1
D D
C C
B B
A A
Title 
Size Document Number Rev
Date: Sheet 
of 
Power Topology 1A
Chassis Manager Assembly V1 
Cloud Server Infrastructure Engineering
C
11 85Monday, January 27, 2014 
Title 
Size Document Number Rev
Date: Sheet 
of 
Power Topology 1A
Chassis Manager Assembly V1 
Cloud Server Infrastructure Engineering
C
11 85Monday, January 27, 2014 
Title 
Size Document Number Rev
Date: Sheet 
of 
Power Topology 1A
Chassis Manager Assembly V1 
Cloud Server Infrastructure Engineering
C
11 85Monday, January 27, 2014 



5
5
4
4
3
3
2
2
1
1
D D
C C
B B
A A
Title 
Size Document Number Rev
Date: Sheet 
of 
Port Pinouts 1A
Chassis Manager Assembly V1 
Cloud Server Infrastructure Engineering
C
12 85Monday, January 27, 2014 
Title 
Size Document Number Rev
Date: Sheet 
of 
Port Pinouts 1A
Chassis Manager Assembly V1 
Cloud Server Infrastructure Engineering
C
12 85Monday, January 27, 2014 
Title 
Size Document Number Rev
Date: Sheet 
of 
Port Pinouts 1A
Chassis Manager Assembly V1 
Cloud Server Infrastructure Engineering
C
12 85Monday, January 27, 2014 



5
5
4
4
3
3
2
2
1
1
D D
C C
B B
A A
Enable SRC 4,6 
Enable PCI, SATA and SRC 
Enable CPU clock 
One 0.1u CAP per pin 
One 0.1u CAP per pin 
One 0.1u CAP per pin 
Enable CLK GEN 
Enable XDP 
Enable SRC 1,2,3 
33.33M PCI output 
SRC5 output 
0
0
0
0
1
1
1 1
FSLC FSLB CPU 
MHZ 
SRC 
MHZ 
PCI 
MHZ 
33.33 
33.33 
33.33 
33.33 
100.00 
100.00 
100.00 
100.00 
133.33 
167.67 
100.00 
200.00 
Enable SRC 5,7,SATA 
FSLB 
FSLC 
I2C Address = 0xD3,0xD2 
FM_CPLD_NODE1_CLK_PG 
PCI_STP_NODE1 
P3V3_CLK_NODE1_R 
CLK_FSLB_NODE1 
P1V05_CLK_NODE1_R 
FM_CPLD_CLK_R_PG_NODE1_R 
CPU_STP_NODE1 
P1V5_CLK_NODE1_R 
CLKREQB_NODE1_N 
CLKREQC_NODE1_N 
XTAL_CLK_NODE1_X2 
XTAL_CLK_NODE1_X1 
XTAL_CLK_NODE1_X2 
XTAL_CLK_NODE1_X1 
CLKREQA_NODE1_N 
PCI_STP_NODE1 
CPU_STP_NODE1 
FM_CPLD_CLK_R_PG_NODE1_R 
CLP_ITP_EN_NODE1 
CLP_ITP_EN_NODE1 
CLKREQA_NODE1_N 
SEL_PCI_27M 
SEL_PCI_27M 
SEL_DOT_SRC5 
SEL_DOT_SRC5 
CLKREQB_NODE1_N 
CLKREQC_NODE1_N 
CLK_14M_CPU_NODE1_R 
CLK_25M_SATA_NODE1_R 
CLK_25M_SATA_NODE1_R 
CLK_14M_CPU_NODE1_R 
CLK_FSLB_NODE1 
CLK_14M_CPU_NODE1_R 
CLKREQC_NODE1_N 
CLP_ITP_EN_NODE1 
FM_CPLD_NODE1_CLK_PG (67) 
CLK_100M_PCIE_RP0_NODE1_DP (15) 
CLK_100M_PCIE_RP0_NODE1_DN (15) 
CLK_100M_DDR3_NODE1_DP (14) 
CLK_100M_DDR3_NODE1_DN (14) 
CLK_100M_XDP_NODE1_DP (29) 
CLK_100M_XDP_NODE1_DN (29) 
SMB_MUX_CPU_ICS_NODE1_DAT (18,26,27) 
SMB_MUX_CPU_ICS_NODE1_CLK (18,26,27) 
CLK_100M_CPU_NODE1_DP (19) 
CLK_100M_CPU_NODE1_DN (19) 
CLK_100M_NIC1_NODE1_DP (49) 
CLK_100M_NIC1_NODE1_DN (49) 
CLK_100M_NIC2_NODE1_DP (50) 
CLK_100M_NIC2_NODE1_DN (50) 
CLK_100M_SATA_NODE1_DP 
CLK_100M_SATA_NODE1_DN 
CLK_100M_USB_NODE1_DP (47) 
CLK_100M_USB_NODE1_DN (47) 
CLK_100M_PCIE_SW_NODE1_DP (30) 
CLK_100M_PCIE_SW_NODE1_DN (30) 
CLK_100M_BMC_NODE1_DP (32) 
CLK_100M_BMC_NODE1_DN (32) 
CLK_25M_SATA_NODE1 
CLK_14M_CPU_NODE1 (19) 
CLK_48M_SIO (52) 
CLK_33M_PORT80 (23) 
P3V3_NODE1 
P3V3_CLK_NODE1 
P1V5_NODE1 P1V5_CLK_NODE1 P1V05_CLK_NODE1 P1V05_NODE1 
P3V3_CLK_NODE1 
P1V5_CLK_NODE1 
P1V05_CLK_NODE1 
P3V3_CLK_NODE1 
P3V3_CLK_NODE1 
P3V3_CLK_NODE1 
P3V3_CLK_NODE1 
P3V3_CLK_NODE1 
P3V3_CLK_NODE1 
P3V3_CLK_NODE1 
P3V3_CLK_NODE1 
P3V3_CLK_NODE1 
P3V3_CLK_NODE1 
Title 
Size Document Number Rev
Date: Sheet 
of 
Clock Gen 1A
Chassis Manager Assembly V1 
Cloud Server Infrastructure Engineering
C
13 85Monday, January 27, 2014 
Title 
Size Document Number Rev
Date: Sheet 
of 
Clock Gen 1A
Chassis Manager Assembly V1 
Cloud Server Infrastructure Engineering
C
13 85Monday, January 27, 2014 
Title 
Size Document Number Rev
Date: Sheet 
of 
Clock Gen 1A
Chassis Manager Assembly V1 
Cloud Server Infrastructure Engineering
C
13 85Monday, January 27, 2014 
R13 
10K R0402 
1% 
NI 
Y1 
25MHZ 
IN 1
GND 4
OUT 3
GND 2
U1 
9VRS4339BKLFT 
VDD25_3.3 3
VDDPCI_3.3 7
VDD14_3.3 14 
VDD48_3.3 15 
vSEL_PCI/27M_PCI4_2X 21 
GNDSRC 40 
SATA#_LPRS 30 
SRC2#_LPRS 41 X1 2
X2 1
SDATA_3.3 5
SCLK_3.3 6
GND48 18 
SATA_LPRS 31 
SRC3_LPRS 37 
CPU_ITP/SRC1_LPRS 47 
GNDPCI 11 
GND14M 12 
CLKREQC#/48M 17 
DOT96#_LPRS/SRC5#_LPRS 24 
VDD_CORE_1.5 25 
VDDSRC_LVIO 34 
SRC7_LPRS 44 
VDD_CORE_1.5 48 
E_PAD TH 
CPU_ITP#/SRC1#_LPRS 46 
CPU_STOP#_3.3 45 
SRC#7_LPRS 43 
SRC2_LPRS 42 
SRC6_LPRS 39 
SRC6#_LPRS 38 
CLKREQB# 19 
VDD27 20 
GND27 22 
DOT96_LPRS/SRC5_LPRS 23 
SRC3#_LPRS 36 
PCI_STOP#_3.3 35 
SRC4_LPRS 33 
SRC4#_LPRS 32 
GNDSATA 29 
GNDLCD 28 
LCD100#_LPRS 27 LCD100_LPRS 26 
25M 4
^DOT96_SEL/USB48M 16 
vITP_EN/PCI_F1_2x 8 FSLB/PCI2_2x 9 CLKREQA#/PCI3_2x 10 
14M_2X/FSLC 13 
VDDCPU_LVIO 49 
CPU1#_LPRS 50 CPU1_LPRS 51 
GNDCPU 52 
CPU0_LPRS 54 
CPU0#_LPRS 53 
CLKPWRGD/PD#_3.3 55 
GND25 56 
R18 
10K R0402 
1% 
NI 
L2 
330/3A 
21 L1 
330/3A 
21
C8 
0.1UF 
X7R 
16V 
10% 
C0402 
C5 
0.1UF 
X7R 
16V 
10% 
C0402 
C196 
0.1UF 
X7R 
16V 
10% 
C0402 
R12 
10K R0402 
1% 
R26 
10K R0402 
1% 
NI 
C2 
0.1UF 
X7R 
16V 
10% 
C0402 
L3 
330/3A 
21R2 0
5% R0603 
R23 
10K R0402 
1% 
R1 0
5% R0603 
R7 0
R0402 5% 
R14 
10K R0402 
1% NI 
R19 
10K R0402 
1% 
NI 
R16 
10K R0402 
1% 
R10 33 
R0402 1% 
C9 
10UF 10V 
20% 
X5R 
C0603 
C6 
10UF 10V 
20% 
X5R 
C0603 
C12 
27PF 
NPO 
50V 
C0402 
5% 
R22 
10K R0402 
1% 
R135 33 
R0402 1% 
R9 33 
R0402 1% 
C7 
0.1UF 
X7R 
16V 
10% 
C0402 
R25 
10K R0402 
1% 
R4 10M 
5% R0402 
R21 
10K R0402 
1% 
NI 
R8 0
R0402 5% 
NI 
C11 
0.1UF 
X7R 
16V 
10% 
C0402 
R188 33 
R0402 1% 
C13 
27PF 
NPO 
50V 
C0402 
5% 
R24 
10K R0402 
1% 
R5 10K 
R0402 1% 
R11 
10K R0402 
1% 
R6 10K 
R0402 1% 
R20 
10K R0402 
1% 
NI 
C1 
10UF 10V 
20% 
X5R 
C0603 
R17 
10K R0402 
1% 
NI 
R3 0
5% R0603 
C10 
0.1UF 
X7R 
16V 
10% 
C0402 
C4 
0.1UF 
X7R 
16V 
10% 
C0402 
R15 
10K R0402 
1% 
C3 
0.1UF 
X7R 
16V 
10% 
C0402 



5
5
4
4
3
3
2
2
1
1
D D
C C
B B
A A
M_DDR3_NODE1_CMDPU 
M_DDR3_NODE1_ODTPU 
M_DDR3_NODE1_MON1P 
M_DDR3_NODE1_MON1N 
M_DDR3_NODE1_MON2P 
M_DDR3_NODE1_MON2N 
M_DDR3_NODE1_BS0 
M_DDR3_NODE1_BS1 
M_DDR3_NODE1_BS2 
M_DDR3_NODE1_CK1P 
M_DDR3_NODE1_CK0P 
M_DDR3_NODE1_CK1N 
M_DDR3_NODE1_CK0N 
M_DDR3_NODE1_CKE1 
M_DDR3_NODE1_CKE0 
M_DDR3_NODE1_CS1_L 
M_DDR3_NODE1_CS0_L 
M_DDR3_NODE1_ODT1 
M_DDR3_NODE1_ODT0 
M_DDR3_NODE1_MON1P 
M_DDR3_NODE1_MON1N 
M_DDR3_NODE1_MON2P 
M_DDR3_NODE1_MON2N 
M_DDR3_NODE1_DQPU 
M_DDR3_NODE1_MA0 (27) 
M1_DQ_NODE1_DQ0 (27) 
M1_DQ_NODE1_DQ1 (27) 
M1_DQ_NODE1_DQ43 (27) 
M1_DQ_NODE1_DQ44 (27) 
M1_DQ_NODE1_DQ47 (27) 
M1_DQ_NODE1_DQ48 (27) 
M1_DQ_NODE1_DQ45 (27) 
M1_DQ_NODE1_DQ46 (27) 
M1_DQ_NODE1_DQ42 (27) 
M1_DQ_NODE1_DQ51 (27) 
M1_DQ_NODE1_DQ52 (27) 
M1_DQ_NODE1_DQ55 (27) 
M1_DQ_NODE1_DQ56 (27) 
M1_DQ_NODE1_DQ53 (27) 
M1_DQ_NODE1_DQ54 (27) 
M1_DQ_NODE1_DQ59 (27) 
M1_DQ_NODE1_DQ60 (27) 
M1_DQ_NODE1_DQ63 (27) 
M1_DQ_NODE1_DQ61 (27) 
M1_DQ_NODE1_DQ62 (27) 
M1_DQ_NODE1_DQ57 (27) 
M1_DQ_NODE1_DQ58 (27) 
M1_DQ_NODE1_DQ49 (27) 
M1_DQ_NODE1_DQ50 (27) 
M1_DQ_NODE1_DQ40 (27) 
M1_DQ_NODE1_DQ41 (27) 
M1_DQ_NODE1_DQ2 (27) 
M1_DQ_NODE1_DQ3 (27) 
M1_DQ_NODE1_DQ34 (27) 
M1_DQ_NODE1_DQ35 (27) 
M1_DQ_NODE1_DQ38 (27) 
M1_DQ_NODE1_DQ39 (27) 
M1_DQ_NODE1_DQ36 (27) 
M1_DQ_NODE1_DQ37 (27) 
M1_DQ_NODE1_DQ32 (27) 
M1_DQ_NODE1_DQ33 (27) 
M1_DQ_NODE1_DQ6 (27) 
M1_DQ_NODE1_DQ7 (27) 
M1_DQ_NODE1_DQ4 (27) 
M1_DQ_NODE1_DQ5 (27) 
M1_DQ_NODE1_DQ10 (27) 
M1_DQ_NODE1_DQ11 (27) 
M1_DQ_NODE1_DQ14 (27) 
M1_DQ_NODE1_DQ15 (27) 
M1_DQ_NODE1_DQ12 (27) 
M1_DQ_NODE1_DQ13 (27) 
M1_DQ_NODE1_DQ8 (27) 
M1_DQ_NODE1_DQ9 (27) 
M1_DQ_NODE1_DQ18 (27) 
M1_DQ_NODE1_DQ19 (27) 
M1_DQ_NODE1_DQ22 (27) 
M1_DQ_NODE1_DQ23 (27) 
M1_DQ_NODE1_DQ20 (27) 
M1_DQ_NODE1_DQ21 (27) 
M1_DQ_NODE1_DQ26 (27) 
M1_DQ_NODE1_DQ27 (27) 
M1_DQ_NODE1_DQ30 (27) 
M1_DQ_NODE1_DQ31 (27) 
M1_DQ_NODE1_DQ28 (27) 
M1_DQ_NODE1_DQ29 (27) 
M1_DQ_NODE1_DQ24 (27) 
M1_DQ_NODE1_DQ25 (27) 
M1_DQ_NODE1_DQ16 (27) 
M1_DQ_NODE1_DQ17 (27) 
CLK_100M_DDR3_NODE1_DP (13) 
CLK_100M_DDR3_NODE1_DN (13) 
PWRGD_NODE1_DDR3_SYSPWRGD (68) 
M_DDR3_NODE1_RAS_L (27) 
M_DDR3_NODE1_MA1 (27) 
M_DDR3_NODE1_MA2 (27) 
M_DDR3_NODE1_MA3 (27) 
M_DDR3_NODE1_MA4 (27) 
M_DDR3_NODE1_MA5 (27) 
M_DDR3_NODE1_MA6 (27) 
M_DDR3_NODE1_MA7 (27) 
M_DDR3_NODE1_MA8 (27) 
M_DDR3_NODE1_MA9 (27) 
M_DDR3_NODE1_MA10 (27) 
M_DDR3_NODE1_MA11 (27) 
M_DDR3_NODE1_MA12 (27) 
M_DDR3_NODE1_MA13 (27) 
M_DDR3_NODE1_MA14 (27) 
M_DDR3_NODE1_MA15 (27) 
M_DDR3_NODE1_DQS0P (27) 
M_DDR3_NODE1_DQS1P (27) 
M_DDR3_NODE1_DQS2P (27) 
M_DDR3_NODE1_DQS3P (27) 
M_DDR3_NODE1_DQS4P (27) 
M_DDR3_NODE1_DQS5P (27) 
M_DDR3_NODE1_DQS6P (27) 
M_DDR3_NODE1_DQS7P (27) 
M_DDR3_NODE1_DQS3N (27) 
M_DDR3_NODE1_DQS4N (27) 
M_DDR3_NODE1_DQS5N (27) 
M_DDR3_NODE1_DQS6N (27) 
M_DDR3_NODE1_DQS7N (27) 
M_DDR3_NODE1_DQS0N (27) 
M_DDR3_NODE1_DQS1N (27) 
M_DDR3_NODE1_DQS2N (27) 
M_DDR3_NODE1_ECC0 (27) 
M_DDR3_NODE1_ECC1 (27) 
M_DDR3_NODE1_ECC3 (27) 
M_DDR3_NODE1_ECC2 (27) 
M_DDR3_NODE1_ECC5 (27) 
M_DDR3_NODE1_ECC7 (27) 
M_DDR3_NODE1_ECC6 (27) 
M_DDR3_NODE1_ECC4 (27) 
PWRGD_NODE1_DDR3_DRAM_POK (68) 
M_DDR3_NODE1_DQSECCN (27) 
M_DDR3_NODE1_DQSECCP (27) 
M_NODE1_DIMM_RST_L (27) 
M_DDR3_NODE1_BS0 (27) 
M_DDR3_NODE1_BS1 (27) 
M_DDR3_NODE1_BS2 (27) 
M_DDR3_NODE1_CK1P (27) 
M_DDR3_NODE1_CK0P (27) 
M_DDR3_NODE1_CK1N (27) 
M_DDR3_NODE1_CK0N (27) 
M_DDR3_NODE1_CKE1 (27) 
M_DDR3_NODE1_CKE0 (27) 
M_DDR3_NODE1_CS1_L (27) 
M_DDR3_NODE1_CS0_L (27) 
M_DDR3_NODE1_ODT1 (27) 
M_DDR3_NODE1_ODT0 (27) 
M_DDR3_NODE1_CAS_L (27) 
M_DDR3_NODE1_WE_L (27) 
PV_VDDR_NODE1 
Title 
Size Document Number Rev
Date: Sheet 
of 
Node1 CPU DDR3 Interface 1A
Chassis Manager Assembly V1 
Cloud Server Infrastructure Engineering
C
14 85Monday, January 27, 2014 
Title 
Size Document Number Rev
Date: Sheet 
of 
Node1 CPU DDR3 Interface 1A
Chassis Manager Assembly V1 
Cloud Server Infrastructure Engineering
C
14 85Monday, January 27, 2014 
Title 
Size Document Number Rev
Date: Sheet 
of 
Node1 CPU DDR3 Interface 1A
Chassis Manager Assembly V1 
Cloud Server Infrastructure Engineering
C
14 85Monday, January 27, 2014 
Processor 
U2A 
DDR3_DQ63 AL65 
DDR3_DQ62 AL62 
DDR3_DQ61 AR63 
DDR3_DQ60 AL63 
DDR3_DQ59 AN65 
DDR3_DQ58 AR65 
DDR3_DQ57 AT64 
DDR3_DQ56 AT63 
DDR3_DQ55 BC64 
DDR3_DQ54 BD63 
DDR3_DQ53 AW64 
DDR3_DQ52 AY63 
DDR3_DQ51 AW62 
DDR3_DQ50 BE64 
DDR3_DQ49 AY65 
DDR3_DQ48 BD65 
DDR3_DQ47 BE57 
DDR3_DQ46 BH57 
DDR3_DQ45 BB60 
DDR3_DQ44 BB57 
DDR3_DQ43 BD60 
DDR3_DQ42 BG58 
DDR3_DQ41 BB59 
DDR3_DQ40 BH58 
DDR3_DQ39 BM54 
DDR3_DQ38 BL53 
DDR3_DQ37 BL59 
DDR3_DQ36 BL57 
DDR3_DQ35 BN57 
DDR3_DQ34 BN53 
DDR3_DQ33 BM58 
DDR3_DQ32 BM52 
DDR3_DQ31 BL26 
DDR3_DQ30 BL23 
DDR3_DQ29 BL28 
DDR3_DQ28 BP22 
DDR3_DQ27 BM27 
DDR3_DQ26 BN23 
DDR3_DQ25 BN28 
DDR3_DQ24 BM22 
DDR3_DQ23 BG29 
DDR3_DQ22 BA29 
DDR3_DQ21 BB25 
DDR3_DQ20 BH26 
DDR3_DQ19 BB26 
DDR3_DQ18 BG25 
DDR3_DQ17 BA25 
DDR3_DQ16 BH25 
DDR3_DQ15 BL17 
DDR3_DQ14 BL14 
DDR3_DQ13 BN19 
DDR3_DQ12 BP13 
DDR3_DQ11 BM18 
DDR3_DQ10 BN14 
DDR3_DQ9 BL19 
DDR3_DQ8 BM13 
DDR3_DQ7 BF13 
DDR3_DQ6 BD13 
DDR3_DQ5 BG21 
DDR3_DQ4 BG19 
DDR3_DQ3 BH19 
DDR3_DQ2 BG15 
DDR3_DQ1 BF21 
DDR3_DQ0 BG13 
DDR3_CLKREFN BF45 
DDR3_CLKREFP BG45 
DDR3_SYSPWRGOOD BG32 
DDR3_VREF BH41 
DDR3_RAS# BP43 
DDR3_CAS# BN46 
DDR3_WE# BL44 
DDR3_MA15 BP31 
DDR3_MA14 BM31 
DDR3_MA13 BN48 
DDR3_MA12 BL32 
DDR3_MA11 BL34 
DDR3_MA10 BN41 
DDR3_MA9 BM34 
DDR3_MA8 BN35 
DDR3_MA7 BL35 
DDR3_MA6 BP37 
DDR3_MA5 BN37 
DDR3_MA4 BN39 
DDR3_MA3 BL37 
DDR3_MA2 BP40 
DDR3_MA1 BL39 
DDR3_MA0 BK40 
DDR3_DQS7 AN63 
DDR3_DQS6 BB63 
DDR3_DQS5 BH62 
DDR3_DQS4 BL55 
DDR3_DQS3 BN26 
DDR3_DQS2 BE26 
DDR3_DQS1 BN17 
DDR3_DQS0 BG17 
DDR3_DQS#7 AP64 
DDR3_DQS#6 BB65 
DDR3_DQS#5 BF62 
DDR3_DQS#4 BN55 
DDR3_DQS#3 BM25 
DDR3_DQS#2 BD26 
DDR3_DQS#1 BM16 
DDR3_DQS#0 BH17 
DDR3_ECC7 BK49 
DDR3_ECC6 BH49 
DDR3_ECC5 BA50 
DDR3_ECC4 BD49 
DDR3_ECC3 BD50 
DDR3_ECC2 BK51 
DDR3_ECC1 BB49 
DDR3_ECC0 BG50 
DDR3_MON1P BG37 
DDR3_MON1N BG38 
DDR3_MON2P BF37 
DDR3_MON2N BF38 
DDR3_BS2 BN32 
DDR3_BS1 BL41 
DDR3_BS0 BL43 
DDR3_CK1 BG41 
DDR3_CK0 BD41 
DDR3_CK#1 BG42 
DDR3_CK#0 BD42 
DDR3_CKE1 BK45 
DDR3_CKE0 BL46 
DDR3_CS#1 BP46 
DDR3_CS#0 BN44 
DDR3_ODT1 BP49 
DDR3_ODT0 BL48 
DDR3_CMDPU BH34 
DDR3_DQPU BG34 
DDR3_ODTPU BH32 
DDR3_DQSECC BE49 
DDR3_DQSECC# BG49 
DDR3_DRAMRST# BC38 
DDR3_DRAM_PWROK BH42 
R29 34 1% R0402 
R34 
100 
1% 
R0402 
R30 274 R0402 1% 
R27 
100 
1% 
R0402 
R35 
100 
1% 
R0402 
NI 
R28 31.6 1% R0402 
R31 
100 
1% 
R0402 
R32 
100 
1% 
R0402 
C14 
0.1UF 
X7R 
C0402 
10% 
16V 
R33 
100 
1% 
R0402 
NI 



5
5
4
4
3
3
2
2
1
1
D D
C C
B B
A A
PCIE SW 
SATA 
NIC 
PCIE SW 
SATA 
NIC 
TP_CPU_NODE1_RP0_PLLMON1 
TP_CPU_NODE1_RP0_PLLMON0 
A_NODE1_RP0_RCOMP 
PD_CPU_NODE1_RP1_PERP 
PD_CPU_NODE1_RP1_PERN 
PD_CPU_NODE1_RP1_PERP 
PD_CPU_NODE1_RP1_PERN 
PD_CPU_NODE1_RP1_PERP 
PD_CPU_NODE1_RP1_PERN 
PD_CPU_NODE1_RP1_PERP 
PD_CPU_NODE1_RP1_PERN 
PD_CPU_NODE1_RP1_PERP 
PD_CPU_NODE1_RP1_PERN 
PD_CPU_NODE1_RP1_PERP 
PD_CPU_NODE1_RP1_PERN 
PD_CPU_NODE1_RP1_PERP 
PD_CPU_NODE1_RP1_PERN 
PD_CPU_NODE1_RP1_PERP 
PD_CPU_NODE1_RP1_PERN 
PD_CPU_NODE1_RP1_PERP 
PD_CPU_NODE1_RP1_PERN 
PD_CPU_NODE1_AN5 
PD_CPU_NODE1_AL5 
PD_CPU_NODE1_AM23 
PD_CPU_NODE1_RP2_PERP 
PD_CPU_NODE1_RP2_PERN 
PD_CPU_NODE1_RP2_PERP 
PD_CPU_NODE1_RP2_PERN 
PD_CPU_NODE1_RP2_PERP 
PD_CPU_NODE1_RP2_PERN 
PD_CPU_NODE1_RP2_PERP 
PD_CPU_NODE1_RP2_PERN 
PD_CPU_NODE1_RP2_PERP 
PD_CPU_NODE1_RP2_PERN 
PD_CPU_NODE1_RP2_PERP 
PD_CPU_NODE1_RP2_PERN 
PD_CPU_NODE1_RP2_PERP 
PD_CPU_NODE1_RP2_PERN 
PD_CPU_NODE1_RP2_PERP 
PD_CPU_NODE1_RP2_PERN 
PD_CPU_NODE1_Y2 
PD_CPU_NODE1_W1 
PD_CPU_NODE1_AJ23 
PD_CPU_NODE1_RP2_PERN 
PD_CPU_NODE1_RP2_PERP 
TP_CPU_NODE1_RP0_PERP1 
TP_CPU_NODE1_RP0_PERN1 
TP_CPU_NODE1_RP0_PERP3 
TP_CPU_NODE1_RP0_PERN3 
TP_CPU_NODE1_RP0_PERP5 
TP_CPU_NODE1_RP0_PERN5 
TP_CPU_NODE1_RP0_PERP7 
TP_CPU_NODE1_RP0_PERN7 
P2E_CPU_PCIE_SW_NODE1_TX_C_DN 
P2E_CPU_SATA_NODE1_TX_C_DP 
P2E_CPU_SATA_NODE1_TX_C_DN 
P2E_CPU_PCIE_SW_NODE1_TX_C_DP 
P2E_CPU_NIC1_NODE1_TX_C_DN 
P2E_CPU_NIC1_NODE1_TX_C_DP 
TP_CPU_NODE1_RP0_PETP5 
TP_CPU_NODE1_RP0_PETN5 
TP_CPU_NODE1_RP0_PETP3 
TP_CPU_NODE1_RP0_PETN3 
TP_CPU_NODE1_RP0_PETP1 
TP_CPU_NODE1_RP0_PETN1 
TP_CPU_NODE1_RP0_PETP7 
TP_CPU_NODE1_RP0_PETN7 
P2E_CPU_SATA_NODE1_TX_C_DP 
P2E_CPU_SATA_NODE1_TX_C_DN 
P2E_CPU_NIC1_NODE1_TX_C_DN 
P2E_CPU_NIC1_NODE1_TX_C_DP 
P2E_CPU_NIC2_NODE1_TX_C_DN 
P2E_CPU_NIC2_NODE1_TX_C_DP 
P2E_CPU_NIC2_NODE1_TX_C_DN 
P2E_CPU_NIC2_NODE1_TX_C_DP 
P2E_CPU_PCIE_SW_NODE1_TX_C_DN 
P2E_CPU_PCIE_SW_NODE1_TX_C_DP 
CLK_100M_PCIE_RP0_NODE1_DP (13) 
CLK_100M_PCIE_RP0_NODE1_DN (13) 
P2E_CPU_PCIE_SW_NODE1_RX_DP 
P2E_CPU_PCIE_SW_NODE1_RX_DN 
P2E_CPU_SATA_NODE1_RX_DP (45) 
P2E_CPU_SATA_NODE1_RX_DN (45) 
P2E_CPU_NIC1_NODE1_RX_DP (49) 
P2E_CPU_NIC1_NODE1_RX_DN (49) 
P2E_CPU_NIC2_NODE1_RX_DP (50) 
P2E_CPU_NIC2_NODE1_RX_DN (50) 
P2E_CPU_PCIE_SW_NODE1_TX_DP (30) 
P2E_CPU_PCIE_SW_NODE1_TX_DN (30) 
P2E_CPU_NIC1_NODE1_TX_DP (49) 
P2E_CPU_NIC1_NODE1_TX_DN (49) 
P2E_CPU_SATA_NODE1_TX_DP 
P2E_CPU_SATA_NODE1_TX_DN 
P2E_CPU_NIC2_NODE1_TX_DP (50) 
P2E_CPU_NIC2_NODE1_TX_DN (50) 
P1V5_NODE1 
Title 
Size Document Number Rev
Date: Sheet 
of 
Node1 CPU PCIe Interface 1A
Chassis Manager Assembly V1 
Cloud Server Infrastructure Engineering
C
15 85Monday, January 27, 2014 
Title 
Size Document Number Rev
Date: Sheet 
of 
Node1 CPU PCIe Interface 1A
Chassis Manager Assembly V1 
Cloud Server Infrastructure Engineering
C
15 85Monday, January 27, 2014 
Title 
Size Document Number Rev
Date: Sheet 
of 
Node1 CPU PCIe Interface 1A
Chassis Manager Assembly V1 
Cloud Server Infrastructure Engineering
C
15 85Monday, January 27, 2014 
R43 
10K R0402 
1% 
R45 
10K R0402 
1% 
C17 0.1UF 
X7R C0402 
10% 16V 
C21 0.1UF 
X7R C0402 
10% 16V 
R46 
10K R0402 
1% 
R39 
10K R0402 
1% 
Processor 
U2B 
RP0_PERP7 AY2 
RP0_PERN7 AY4 
RP0_PERP6 BB5 
RP0_PERN6 AY5 
RP0_PERP5 BB4 
RP0_PERN5 BB2 
RP0_PERP4 BD2 
RP0_PERN4 BD4 
RP0_PERP3 BF3 
RP0_PERN3 BF1 
RP0_PERP2 BH3 
RP0_PERN2 BJ4 
RP0_PERP1 BL7 
RP0_PERN1 BM7 
RP0_PERP0 BN10 
RP0_PERN0 BM9 
RP0_CLKINP BE5 
RP0_CLKINN BF4 
RP0_PLLMON1 BM3 
RP0_PLLMON0 BM5 
RP0_RCOMP AT23 
TESTLO_16_1 AF4 
TESTLO_08_1 AF2 
TESTLO_16_3 AH3 
TESTLO_08_2 AH1 
TESTLO_16_2 AG5 
TESTLO_08_3 AH4 
TESTLO_16_4 AL2 
TESTLO_08_4 AL4 
TESTLO_16_5 AN4 
TESTLO_08_5 AN2 
TESTLO_16_6 AR4 
TESTLO_08_7 AT5 
TESTLO_16_7 AU3 
TESTLO_08_6 AR2 
TESTLO_16_8 AV2 
TESTLO_08_8 AU1 
TESTLO_06 AN5 
TESTLO_05 AL5 
NC#AR14 AR14 
NC#AR16 AR16 
TESTLO_07 AM23 
TESTLO_17_1 N4 
TESTLO_12_1 N2 
TESTLO_17_2 N5 
TESTLO_12_3 R5 
TESTLO_17_3 R4 
TESTLO_12_2 R2 
TESTLO_17_4 U4 
TESTLO_12_4 U2 
TESTLO_17_5 V5 
TESTLO_12_5 W4 
TESTLO_17_6 AB2 
TESTLO_12_6 AB4 
TESTLO_17_7 AB5 
TESTLO_12_8 AD5 
TESTLO_17_8 AD2 
TESTLO_12_7 AD4 
TESTLO_10 Y2 
TESTLO_09 W1 
NC#Y8 Y8 
NC#W8 W8 
TESTLO_11 AJ23 
RP0_PETP7 AW9 
RP0_PETN7 AW11 
RP0_PETP6 AY11 
RP0_PETN6 AY9 
RP0_PETP5 BC8 
RP0_PETN5 BC10 
RP0_PETP4 BD10 
RP0_PETN4 BD8 
RP0_PETP3 BG8 
RP0_PETN3 BG9 
RP0_PETP2 BH8 
RP0_PETN2 BK9 
RP0_PETP1 BD17 
RP0_PETN1 BB17 
RP0_PETP0 BD19 
RP0_PETN0 BB19 
NC#AL11 AL11 
NC#AL9 AL9 
NC#AM9 AM9 
NC#AM11 AM11 
NC#AL15 AL15 
NC#AL14 AL14 
NC#AM15 AM15 
NC#AM14 AM14 
NC#AR8 AR8 
NC#AR10 AR10 
NC#AT10 AT10 
NC#AT8 AT8 
NC#AT14 AT14 
NC#AT13 AT13 
NC#AW14 AW14 
NC#AW15 AW15 
NC#AC15 AC15 
NC#AC14 AC14 
NC#AC11 AC11 
NC#AC9 AC9 
NC#AD11 AD11 
NC#AD9 AD9 
NC#AD14 AD14 
NC#AD15 AD15 
NC#AG13 AG13 
NC#AG14 AG14 
NC#AG10 AG10 
NC#AG8 AG8 
NC#AH10 AH10 
NC#AH8 AH8 
NC#AH14 AH14 
NC#AH13 AH13 
R44 
10K R0402 
1% 
C18 0.1UF 
X7R C0402 
10% 16V 
R38 
10K R0402 
1% 
C16 0.1UF 
X7R C0402 
10% 16V 
NI 
R40 
10K R0402 
1% 
C22 0.1UF 
X7R C0402 
10% 16V 
R41 
10K R0402 
1% 
C19 0.1UF 
X7R C0402 
10% 16V 
R37 
10K R0402 
1% 
R36 7.5K 
1% R0402 
C20 0.1UF 
X7R C0402 
10% 16V 
C15 0.1UF 
X7R C0402 
10% 16V 
NI 
R42 
10K R0402 
1% 



5
5
4
4
3
3
2
2
1
1
D D
C C
B B
A A
TPM 
SIO 
     ID0   ID1  ID2 
EVT   0      0    0 
DVT   0      0    1* 
PVT   0      1    1 
MP    1      0    0 
SPC_CPU_NODE1_DCD_L 
SPC_CPU_NODE1_DSR_L 
SPC_CPU_NODE1_CTS_L 
A_CPU_NODE1_RTC_EXTPAD 
SPC_CPU_NODE1_RI_L 
SPC_CPU_NODE1_RI_L 
SPI_CPU_NODE1_WP_R_L 
SPC_CPU_NODE1_DTR_L 
SPI_CPU_NODE1_WP_L 
LPC_CPU_NODE1_FRAME_L_R 
LPC_CPU_NODE1_CLKRUN_L 
LPC_CPU_NODE1_R_CLKOUT1 
SPC_CPU_NODE1_DCD_L 
SPC_CPU_NODE1_CTS_L 
VR_NODE1_VDDR_1V5_CNTL 
LPC_CPU_NODE1_CLKRUN_L SPC_CPU_NODE1_RTS_L 
SPI_CPU_NODE1_SCLK_R 
SPI_CPU_NODE1_MOSI_R 
CONSOLE_SELECT_N 
NODE1_BIOS_MB_REV_ID1 
NODE1_BIOS_MB_REV_ID0 
XTAL_CPU_NODE1_X2PAD 
CPU_RSV_1_R 
LPC_CPU_NODE1_LAD3_R 
LPC_CPU_NODE1_LAD2_R 
LPC_CPU_NODE1_LAD1_R 
LPC_CPU_NODE1_LAD0_R 
XDP_SOC_CPU_NODE1_TCK 
NODE1_BIOS_MB_REV_ID2 
TP_CPU_E59 
TP_CPU_D53 
LPC_CPU_NODE1_R_CLKOUT0 
SPC_CPU_NODE1_DSR_L 
TP_SPI_CPU_NODE1_CS1_L 
XTAL_CPU_NODE1_X1PAD 
SPI_CPU_NODE1_SCLK 
SPI_CPU_NODE1_MOSI SPI_CPU_NODE1_CS0_R_L 
IRQ_CPU_NODE1_SERIAL_R 
NODE1_BIOS_MB_REV_ID1 
NODE1_BIOS_MB_REV_ID0 
NODE1_BIOS_MB_REV_ID2 
CPU_RSV_1_R 
H_CPU_NODE1_ERR2 
H_CPU_NODE1_ERR1 
H_CPU_NODE1_ERR0 TP_CPU_NODE1_K62 
TP_CPU_NODE1_M52 
CONSOLE_SELECT_N 
LPC_CPU_NODE1_CLK0_DS (22) 
SPI_CPU_NODE1_CS0_L (23) 
XDP_SOC_CPU_NODE1_TCK (29) 
XDP_SOC_CPU_NODE1_TCK 
VR_CPU_NODE1_INTVRMEN (22) 
VR_NODE1_VDDR_1V5_CNTL (80) 
XDP_SOC_CPU_NODE1_TMS (29) 
SPI_CPU_NODE1_WP_L (23) 
XDP_SOC_CPU_NODE1_TMS 
XDP_SOC_CPU_NODE1_TDI 
IRQ_CPU_NODE1_SERIAL (23,52) 
USB_NODE1_SMI_L (47) 
XDP_SOC_CPU_NODE1_TDO (29) 
PD_CPU_NODE1_BOOTDEVSEL (22) 
LPC_CPU_NODE1_LAD3 (23,52) 
LPC_CPU_NODE1_LAD2 (23,52) 
LPC_CPU_NODE1_LAD1 (23,52) 
LPC_CPU_NODE1_LAD0 (23,52) 
FM_CPU_NODE1_JTAG_POK (68) 
IRQ_CPU_NODE1_SERIAL (23,52) 
XDP_SOC_CPU_NODE1_TDI (29) 
FM_CPLD_NODE1_PWR_BTN_CPU (67) 
VR_NODE1_VDDR_1V5_CNTL (80) 
SPI_CPU_NODE1_MISO (23) 
PD_CPU_NODE1_BRD_ID1 (22) 
PU_CPU_NODE1_BRD_ID0 (22) 
LPC_CPU_NODE1_CLKOUT0 (23) 
PD_CPU_NODE1_NODE_ID (22) 
RST_CPU_NODE1_SRTCRST_L (22,67) 
SPI_CPU_NODE1_MOSI (23) 
SPI_CPU_NODE1_SCLK (23) 
XDP_SOC_CPU_NODE1_TRST_L (29) 
LPC_CPU_NODE1_FRAME_L (23,52) 
LAN1_DISABLE_N 
LAN2_DISABLE_N 
PCIE_SW_P0_ERR 
SMB_TEMP1_NODE1_ALERT_L (26) 
SMB_BMC_NODE1_HSC_ALERT_L (66) 
CPU_RSV_1 (60) 
CPLD_ROW_LATCH (67) 
CPLD_ROW_EN (67) 
LPC_CPU_NODE1_CLKOUT1 (52) 
CPU_NODE1_PROCHOT_N (18) 
H_CPU_NODE1_ERR0_R 
H_CPU_NODE1_ERR1_R 
H_CPU_NODE1_ERR2_R 
P3V3_NODE1 
P3V3_SUS_NODE1 
P3V3_NODE1 
P1V05_NODE1 
P3V3_NODE1 
P3V3_NODE1 
P3V3_NODE1 
P3V3_SUS_NODE1 
P3V3_SUS_NODE1 
Title 
Size Document Number Rev
Date: Sheet 
of 
Node1 CPU GPIO LPC UART 1A
Chassis Manager Assembly V1 
Cloud Server Infrastructure Engineering
C
16 85Monday, January 27, 2014 
Title 
Size Document Number Rev
Date: Sheet 
of 
Node1 CPU GPIO LPC UART 1A
Chassis Manager Assembly V1 
Cloud Server Infrastructure Engineering
C
16 85Monday, January 27, 2014 
Title 
Size Document Number Rev
Date: Sheet 
of 
Node1 CPU GPIO LPC UART 1A
Chassis Manager Assembly V1 
Cloud Server Infrastructure Engineering
C
16 85Monday, January 27, 2014 
C23 0.1UF 
X7R C0402 
10% 16V 
R96 4.7K 
5% R0402 
R63 51 R0402 1% 
R92 4.7K 
5% R0402 
NI 
R87 499 R0402 1% 
R77 10K 
1% R0402 
R74 51 
1% R0402 
R58 15 R0402 5% 
Processor 
U2C 
DFX_GPIO_GRP0_7 J30 
DFX_GPIO_GRP0_6 E28 
DFX_GPIO_GRP0_5 H30 
DFX_GPIO_GRP0_4 H32 
DFX_GPIO_GRP0_3 B30 
DFX_GPIO_GRP0_2 B28 
DFX_GPIO_GRP0_1 D28 
DFX_GPIO_GRP0_0 D30 
GPIOSUS8 N50 
GPIOSUS7 L60 
GPIOSUS6 K62 
GPIOSUS5 M60 
GPIOSUS4 M59 
GPIOSUS3 P50 
GPIOSUS2 M56 
GPIOSUS1 L59 
GPIOSUS0 M52 
JTA_POWEROK AC53 
SOC_TRST# AA62 
SOC_TCK AD62 
SOC_TMS AD63 
SOC_TDI AA66 
RTC_INTVRMEN J64 
RTC_SRTCRST# N62 
SPI_CS#1 E39 
SPI_CS#0 C40 
SPI_MISO E40 
LPC_AD3 H41 
LPC_AD2 H42 
LPC_AD1 G41 
LPC_AD0 G42 
LPCCLK0_DS R63 
LPC_CLKRUN# C42 
LPC_FRAME# D44 
LPC_SERIRQ J46 
BOOTDEVSEL E52 
SPKR H38 
DFX_GPIO_GRP1_7 G32 
DFX_GPIO_GRP1_6 C31 
DFX_GPIO_GRP1_5 E31 
DFX_GPIO_GRP1_4 B35 
DFX_GPIO_GRP1_3 H34 
DFX_GPIO_GRP1_2 G34 
DFX_GPIO_GRP1_1 D33 
DFX_GPIO_GRP1_0 C33 
GPIOCORE20 N48 
GPIOCORE19 L52 
GPIOCORE18 H59 
GPIOCORE17 L54 
GPIOCORE16 H56 
GPIOCORE15 G64 
GPIOCORE14 E59 
GPIOCORE13 E57 
GPIOCORE12 G62 
GPIOCORE11 B55 
GPIOCORE10 D57 
GPIOCORE9 M46 
GPIOCORE8 B57 
GPIOCORE7 D55 
GPIOCORE6 E55 
GPIOCORE5 H54 
GPIOCORE4 H52 
GPIOCORE3 D53 
GPIOCORE2 K48 
GPIOCORE1 K50 
SOC_TDO AA64 
RTC_EXTPAD L65 
RTC_X1PAD R65 
RTC_X2PAD N65 
SPI_MOSI D42 
SPI_SCLK J38 
UART_CTS# C49 
UART_DCD# H46 
UART_DSR# J44 
UART_RI# B48 
UART_RXD D48 
UART_DTR# A48 
UART_RTS# H50 
UART_TXD E48 
LPC_CLKOUT1 C45 
LPC_CLKOUT0 B44 
R195 10K 
R0402 1% 
R61 51 R0402 1% 
R59 15 R0402 5% 
R67 33 
R0402 1% 
R78 
51 
1% 
R0402 
J34 
HEADER 1X2 
1 2
C24 
18PF 50V 
C0G 
C0402 
5% 
R112 10K 
R0402 1% 
NI 
R49 33 
R0402 1% 
R66 51 R0402 1% 
R89 499 R0402 1% 
R72 33 
R0402 1% 
R48 10K 
R0402 1% 
R75 10K 
1% R0402 
R68 10K 
R0402 1% 
R85 499 R0402 1% 
R69 33 
R0402 1% 
R76 51 
1% R0402 
C25 18PF 
50V C0G 
C0402 5% 
R110 0
R0402 5% 
NI 
R62 51 R0402 1% 
R71 33 
R0402 1% 
R65 51 R0402 1% 
R70 10K 
R0402 1% 
R57 0 R0402 5% 
R94 4.7K 
5% R0402 
NI 
R73 33 
R0402 1% 
R90 4.7K 
5% R0402 
Y2 
32.768KHZ 
R88 4.7K 
5% R0402 
R64 
10M 
5% 
R0402 
R86 4.7K 
5% R0402 
NI 
R60 51 R0402 1% 



5
5
4
4
3
3
2
2
1
1
D D
C C
B B
A A
A_CPU_NODE1_HV_GPIO_RCOMP 
A_CPU_NODE1_MV_GPIO_RCOMP 
A_CPU_NODE1_LV_GPIO_RCOMP 
A_CPU_NODE1_AE64_PU 
H_CPU_NODE1_ERR1_R 
H_CPU_NODE1_ERR0_R 
PD_NODE1_NTB_PERP 
PD_NODE1_NTB_PERN 
PD_NODE1_NTB_PERP 
PD_NODE1_NTB_PERN 
PD_NODE1_NTB_PERP 
PD_NODE1_NTB_PERN 
PD_NODE1_NTB_PERP 
PD_NODE1_NTB_PERN 
PD_NODE1_NTB_PERP 
PD_NODE1_NTB_PERN 
PD_NODE1_NTB_PERP 
PD_NODE1_NTB_PERN 
PD_NODE1_NTB_PERP 
PD_NODE1_NTB_PERN 
PD_NODE1_NTB_PERP 
PD_NODE1_NTB_PERN 
PD_NODE1_NTB_PERP 
PD_NODE1_NTB_PERN 
PD_NODE1_NTB_PERP 
PD_NODE1_NTB_PERN 
PD_NODE1_NTB_PERP 
PD_NODE1_NTB_PERN 
PD_NODE1_NTB_PERP 
PD_NODE1_NTB_PERN 
PD_NODE1_NTB_PERP 
PD_NODE1_NTB_PERN 
PD_NODE1_NTB_PERP 
PD_NODE1_NTB_PERN 
PD_NODE1_NTB_PERP 
PD_NODE1_NTB_PERN 
PD_NODE1_NTB_PERP 
PD_NODE1_NTB_PERN 
PD_NODE1_NTB_PERP 
PD_NODE1_NTB_PERN 
PD_NODE1_NTB_CLKINP 
PD_NODE1_NTB_CLKINN 
PD_NODE1_NTB_RCOMP 
A_CPU_NODE1_NTB_CROSSLK_MODE 
H_CPU_NODE1_ERR2_R 
H_CPU_NODE1_ERR1_R 
H_CPU_NODE1_ERR0_R 
P3V3_NODE1 
P1V05_NODE1 
P3V3_NODE1 
P3V3_NODE1 
Title 
Size Document Number Rev
Date: Sheet 
of 
Node1 CPU NTB Interface 1A
Chassis Manager Assembly V1 
Cloud Server Infrastructure Engineering
C
17 85Monday, January 27, 2014 
Title 
Size Document Number Rev
Date: Sheet 
of 
Node1 CPU NTB Interface 1A
Chassis Manager Assembly V1 
Cloud Server Infrastructure Engineering
C
17 85Monday, January 27, 2014 
Title 
Size Document Number Rev
Date: Sheet 
of 
Node1 CPU NTB Interface 1A
Chassis Manager Assembly V1 
Cloud Server Infrastructure Engineering
C
17 85Monday, January 27, 2014 
R100 49.9 1% R0402 R99 10K 1% R0402 
R98 49.9 1% R0402 R97 10K 1% R0402 
R101 49.9 1% R0402 
R111 4.7K 
5% R0402 
R108 10K 
1% R0402 
R104 1K 
1% R0402 
R109 4.7K 
5% R0402 
R102 10K 1% R0402 
R105 4.7K 
5% R0402 
Processor 
U2D 
TESTLO_15_8 D24 
TESTLO_04_9 D26 
TESTLO_15_4 C24 
TESTLO_04_4 B26 
TESTLO_15_7 D23 
TESTLO_04_11 E23 
TESTLO_15_6 D21 
TESTLO_04_3 B21 
TESTLO_15_11 E19 
TESTLO_04_10 E21 
TESTLO_15_5 D19 
TESTLO_04_2 B19 
TESTLO_15_2 B17 
TESTLO_04_8 D17 
TESTLO_15_3 C15 
TESTLO_04_7 D15 
TESTLO_15_10 E12 
TESTLO_04_6 D12 
TESTLO_15_1 B10 
TESTLO_04_1 B12 
TESTLO_15_9 E10 
TESTLO_04_5 D10 
TESTLO_15_15 K10 
TESTLO_04_14 H10 
TESTLO_15_13 H9 
TESTLO_04_13 G9 
TESTLO_15_12 G5 
TESTLO_04_12 F5 
TESTLO_15_14 K4 
TESTLO_04_15 K3 
TESTLO_15_16 L4 
TESTLO_04_16 L2 
TESTLO_02 J14 
TESTLO_01 H14 
NC#J13 J13 
NC#H13 H13 
TESTLO_03 AA23 
TESTLO_00 B41 
NC#G26 G26 
NC#H26 H26 
NC#G25 G25 
NC#H25 H25 
NC#L26 L26 
NC#N26 N26 
NC#N25 N25 
NC#L25 L25 
NC#J22 J22 
NC#L22 L22 
NC#L21 L21 
NC#J21 J21 
NC#G18 G18 
NC#H18 H18 
NC#G17 G17 
NC#H17 H17 
NC#L18 L18 
NC#N18 N18 
NC#L17 L17 
NC#N17 N17 
NC#N8 N8 
NC#N10 N10 
NC#N13 N13 
NC#N14 N14 
NC#R14 R14 
NC#R15 R15 
NC#R9 R9 
NC#R11 R11 
NC#U9 U9 
NC#U11 U11 
NC#U14 U14 
NC#U15 U15 
HV_GPIO_RCOMP M38 
MV_GPIO_RCOMP P34 
LV_GPIO_RCOMP AC47 
TESTHI_1P05 AE64 
EDM AG57 
ERR2 C51 
ERR1 D51 
ERR0 H48 
R103 10K 
1% R0402 
R107 10K 
1% R0402 



5
5
4
4
3
3
2
2
1
1
D D
C C
B B
A A
SVID 
DIMM/CLOCK GEN/THERMAL SENSER/DIMM VREF/FRU
HOT PLUG IC 
I2C Address = 0xA6 
FRU 
Close to U2
TP_CPU0_NODE1_HFPLL 
TP_CPU0_NODE1_SFRANAD 
TP_CPU1_NODE1_HFPLL 
TP_CPU1_NODE1_SFRANAD 
TP_CPU_NODE1_EXTBGREF 
SVID_CPU_NODE1_PVCCP_DAT_R 
SVID_CPU_NODE1_PVCCP_ALERT_R_L 
TP_CPU_NODE1_SOC_THERMATP1 
TP_CPU_NODE1_SOC_THERMATP0 
A_CPU_NODE1_SOC_THERMREFNPAD 
SMB_CPU_NODE1_MEM_ICS_CLK_R 
SMB_CPU_NODE1_MEM_ICS_DAT_R 
SMB_CPU_NODE1_BMC_CLK_RR 
SMB_CPU_NODE1_BMC_DAT_RR 
H_CPU_NODE1_PROCHOT_L 
FRU_SYS_A0 
SMB_MUX_CPU_ICS_NODE1_CLK 
SMB_MUX_CPU_ICS_NODE1_DAT 
H_CPU_NODE1_PROCHOT_L 
SVID_CPU_NODE1_PVCCP_DAT 
H_CPU_NODE1_PROCHOT_R 
FRU_SYS_A1 
FRU_SYS_A2 
FRU_SYS_A1 
FRU_SYS_A0 
FRU_SYS_A2 
XDP_CPU_NODE1_PREQ_L (29) 
XDP_CPU_NODE1_PRDY_L (29) 
A_CPU0_NODE1_THERMDA (26) 
A_CPU0_NODE1_THERMDC (26) 
A_CPU1_NODE1_THERMDA (26) 
A_CPU1_NODE1_THERMDC (26) 
A_SOC_NODE1_THERMDC (26) 
A_SOC_NODE1_THERMDA (26) 
SMB_MUX_CPU_ICS_NODE1_CLK (13,26,27) 
SMB_MUX_CPU_ICS_NODE1_DAT (13,26,27) 
SVID_CPU_NODE1_PVCCP_DAT (81) 
SVID_CPU_NODE1_PVCCP_CLK (81) 
SVID_CPU_NODE1_PVCCP_DAT (81) 
SMB_CPU_NODE1_BMC_CLK (30,66) 
SMB_CPU_NODE1_BMC_DAT (30,66) 
SVID_CPU_NODE1_PVCCP_ALERT_L 
H_CPU_NODE1_THRMTRIP_L (68) 
CPU_NODE1_PROCHOT_N (16) 
P1V05_NODE1 
P3V3_NODE1 
P3V3_NODE1 
P3V3_NODE1 
P3V3_NODE1 
P1V05_NODE1 
P1V05_NODE1 
P1V05_NODE1 P1V05_NODE1 
P1V05_NODE1 
P3V3_NODE1 
P3V3_NODE1 
P1V05_NODE1 
P3V3_NODE1 
P1V05_NODE1
P3V3_NODE1 
P3V3_NODE1 
P3V3_NODE1 
P1V05_NODE1 
Title 
Size Document Number Rev
Date: Sheet 
of 
Node1 CPU SMB SOC 1A
Chassis Manager Assembly V1 
Cloud Server Infrastructure Engineering
C
18 85Monday, January 27, 2014 
Title 
Size Document Number Rev
Date: Sheet 
of 
Node1 CPU SMB SOC 1A
Chassis Manager Assembly V1 
Cloud Server Infrastructure Engineering
C
18 85Monday, January 27, 2014 
Title 
Size Document Number Rev
Date: Sheet 
of 
Node1 CPU SMB SOC 1A
Chassis Manager Assembly V1 
Cloud Server Infrastructure Engineering
C
18 85Monday, January 27, 2014 
C537 
0.1UF 
16V 
10% 
C0402 
R1154 100 
R0402 1% 
R1215 1K 
1% R0402 
R113 51 
1% R0402 
R126 4.7K 
5% R0402 
Processor 
U2E 
PSMI_VISA29 AF63 
PSMI_VISA28 AG63 
PSMI_VISA27 AG64 
PSMI_VISA26 AG60 
PSMI_VISA25 AG66 
PSMI_VISA24 AJ65 
PSMI_VISA23 AL58 
PSMI_VISA22 AJ63 
PSMI_VISA21 AH62 
PSMI_VISA20 AL56 
PSMI_VISA19 AH59 
PSMI_VISA18 AH57 
PSMI_VISA17 AW58 
PSMI_VISA16 AL52 
PSMI_VISA15 AL53 
PSMI_VISA14 AW56 
PSMI_VISA13 AM56 
PSMI_VISA12 AM58 
PSMI_VISA11 AR59 
PSMI_VISA10 AM52 
PSMI_VISA9 AM53 
PSMI_VISA8 AR60 
PSMI_VISA7 AR57 
PSMI_VISA6 AT57 
PSMI_VISA5 AT60 
PSMI_VISA4 AR54 
PSMI_VISA3 AT54 
PSMI_VISA2 AT59 
PSMI_VISA1 AR53 
PSMI_VISA0 AT53 
CPU_PREQ# AE62 
CPU_PRDY# AC52 
CPU0_HFPLL AH50 
CPU0_SFRANAD C36 
CPU0_THERMDA AD39 
CPU0_THERMDC AC38 
CPU1_HFPLL AG50 
CPU1_SFRANAD D35 
CPU1_THERMDA AG39 
CPU1_THERMDC AF38 
CPU_EXTBGREF E36 
CPU_PROCHOT# AC56 
THRMTRIP# AG59 
SVID_CLK AB62 
SVID_DATA AC58 
SVID_ALERT# AB63 
SOC_THERMANATP1 P22 
SOC_THERMANATP0 T18 
SOC_THERMDA R21 
SOC_THERMDC P21 
SOC_THERMREFNPAD R22 
SMBD_CLK W11 
SMBD_DATA W17 
SMBH_CLK Y11 
SMBH_DATA W13 
SMBM_CLK Y13 
SMBM_DATA W16 
R137 432 
1% R0402 
R91 49.9 R0402 1% 
R1216 
1K 
1% 
R0402 
C31 10PF NI 
5% 
50V C0G 
C0402 
R132 33 
1% R0402 
R117 0 5% R0402 
Q42 
PMBT390 
B
EC
R125 33 
R0402 1% 
R118 150 
1% R0402 
R130 33 
1% R0402 
R1153 100 
R0402 1% 
NI U134 
M24C02-WMN6TP 
VCC 8
WP 7
SCL 6
SDA 5 GND 4A2 3A1 2A0 1
R115 240 
1% R0402 
R187 4.7K 
5% R0402 
NI 
R128 33 
R0402 1% 
C29 10PF NI 
5% 
50V C0G 
C0402 
R133 4.7K 
5% R0402 
R114 1K 
1% R0402 
R120 8.06K 
1% R0402 
C30 10PF NI 
5% 
50V C0G 
C0402 
R186 4.7K 
5% R0402 
R200 8.06K 
1% R0402 
NI 
R1151 100 
R0402 1% 
R116 200 
1% R0402 
R180 4.7K 
5% R0402 
R129 4.7K 
5% R0402 
R119 56 
1% R0402 
R127 432 
1% R0402 
C28 10PF NI 
5% 
50V C0G 
C0402 
R131 4.7K 
5% R0402 
R1152 100 
R0402 1% 
NI 



5
5
4
4
3
3
2
2
1
1
D D
C C
B B
A A
Battery Part 
CAD NOTE: 
PLACE 1UF CLOSE 
TO DIODE NEAR 
BATTERY HOLDER 
CLK_33K_CPU_NODE1_SUSCLK_RR 
TP_CPU_NODE1_ADR_COMPLETE 
TP_CPU_NODE1_C2F_LP_MODE 
PWRGD_CPU_NODE1_EPWRGOOD 
TP_CPU_NODE1_IERR_LV 
TP_CPU_NODE1_RSVD_MVT0 
TP_CPU_NODE1_RSVD_MVT1 
TP_CPU_NODE1_HPLL_MONN 
TP_CPU_NODE1_HPLL_MONP 
H_CPU_NODE1_THRM_LS_L 
P3V_COIN_CELL P3V0_BAT_NODE1_R 
FM_CPU_NODE1_SLPRDY_L (67) 
FM_CPU_NODE1_RSTRDY_L (67) 
FM_CPU_NODE1_SLPMODE (67) 
PD_CPU_NODE1_PUNIT_ST_ADDR1 (22) 
PD_CPU_NODE1_PUNIT_ST_ADDR0 (22) 
FM_CPU_NODE1_OWDTOUT (68) 
FM_CPLD_NODE1_CPU_RSMRST_L (67) 
IRQ_LVC3_CPU_NODE1_WAKE_L (32,45,47,49,50,67) 
PD_CPU_NODE1_SPD_EN_L (22) 
PU_CPU_NODE1_MEM_SPEED0 (22) 
PD_CPU_NODE1_HVMGEAR_SEL (22) 
CLK_100M_CPU_NODE1_DP (13) 
CLK_14M_CPU_NODE1 (13) 
PD_CPU_NODE1_MEM_SPEED1 (22) 
CLK_100M_CPU_NODE1_DN (13) 
FM_CPU_NODE1_RSTWARN (67) 
FM_CPLD_NODE1_CPU_RESET_L (67) 
FM_CPLD_NODE1_SYS_PG (67) 
CLK_33K_CPU_NODE1_SUSCLK (67) 
P3V3_RTC_NODE1 
P3V3_NODE1 
P3V3_SUS_NODE1 
P3V3_SUS_NODE1 
P3V3_SUS_NODE1 
P3V3_STB_NODE1 P3V3_RTC_NODE1 
Title 
Size Document Number Rev
Date: Sheet 
of 
Node1 CPU Management Reset 1A
Chassis Manager Assembly V1 
Cloud Server Infrastructure Engineering
C
19 85Monday, January 27, 2014 
Title 
Size Document Number Rev
Date: Sheet 
of 
Node1 CPU Management Reset 1A
Chassis Manager Assembly V1 
Cloud Server Infrastructure Engineering
C
19 85Monday, January 27, 2014 
Title 
Size Document Number Rev
Date: Sheet 
of 
Node1 CPU Management Reset 1A
Chassis Manager Assembly V1 
Cloud Server Infrastructure Engineering
C
19 85Monday, January 27, 2014 
R138 10K 
1% R0402 
R134 10K 
1% R0402 
R147 1K 
1% R0402 
BT1 
Battery connector 
1 2
R142 10K 
1% R0402 
U3 
BAT54C 
2
1
3
BT1_BATTERY1 
AHL03003002 
1
R139 33 
R0402 1% 
NI 
C34 
22UF 
20% 
6.3V 
X5R 
C0805_H61 
R136 10K 
1% R0402 
C32 
1UF 10V 
10% 
C0402 
X5R 
R140 10K 
1% R0402 
Processor 
U2F 
RSTWARN T53 
SLPRDY# R58 
RSTRDY# M54 
SLPMODE R56 
SUSCLK T52 
PUNIT_ST_ADDR1 AH48 
PUNIT_ST_ADDR0 AG48 
NC#B53 B53 
TESTLO_14 A51 
EPWRGOOD AD58 
PWROK J63 
RESET# T58 
TESTLO_13 E49 
HPET_CLK14IN P46 
HPLL_CLKREFP V21 
HPLL_CLKREFN V20 
HVMGEAR_SEL AD52 
MEM_SPEED1 AD53 
MEM_SPEED0 AD56 
CPU_IERR AG54 
NC#AG53 AG53 
NC#AH54 AH54 
OWDTOUT AH53 
RSVD_MVT1 H37 
RSVD_MVT0 B39 
HPLL_MONP F1 
HPLL_MONN H1 
THRM# J37 
RSMRST# L63 
RTCRESET# R62 
SPD_EN# AD49 
WAKE# T56 
R143 10K 
1% R0402 
R144 4.7K 
5% R0402 
C33 
1UF 10V 
10% 
C0402 
X5R 
R141 1K 
1% R0402 



5
5
4
4
3
3
2
2
1
1
D D
C C
B B
A A
TP_CPU_NODE1_VCCCPU0VIDSI0GT1P05_1 
TP_CPU_NODE1_VCCCPU0VIDSI0GT1P05_2 
TP_CPU_NODE1_VCCCPU1VIDSI0GT1P05_2 
TP_CPU_NODE1_VCCCPU1VIDSI0GT1P05_1 
P1V5_NODE1_AM21 
P1V5_NODE1_AA21 
P1V5_NODE1_AJ21 
TP_P1V8_VCCABGTS_NODE1 
P1V05_SUS_NODE1 
P1V05_VCCACLK_DDR3_NODE1 
P1V05_VCCPLL_DDR3_NODE1 
P1V05_NODE1 
P1V05_NODE1 
P1V05_NODE1 
P1V05_NODE1 
PV_VCCP_NODE1 
P1V05_NODE1 
P1V8_NODE1 
P1V8_SUS_NODE1 
P1V8_VCCASFRHPLL_NODE1 
P3V3_NODE1 
P3V3_SUS_NODE1 
P3V3_RTC_NODE1 
P1V05_NODE1 
P1V05_NODE1 
P1V05_VCCPLLCPU0SIO_NODE1 
P1V05_VCCPLLCPU1SIO_NODE1 
P1V05_NODE1 
PV_VDDR_NODE1 
PV_VDDR_VCCCLK_DDR3_NODE1 
P1V5_NODE1 
P1V05_NODE1 
P1V5_SFRPLL_NODE1 
P1V5_NODE1 
P1V5_NODE1 
P1V5_NODE1 
P1V5_NODE1 
P1V5_NODE1 
P1V5_NODE1 
P1V5_NODE1 
Title 
Size Document Number Rev
Date: Sheet 
of 
Node1 CPU Power Rails 1A
Chassis Manager Assembly V1 
Cloud Server Infrastructure Engineering
C
20 85Monday, January 27, 2014 
Title 
Size Document Number Rev
Date: Sheet 
of 
Node1 CPU Power Rails 1A
Chassis Manager Assembly V1 
Cloud Server Infrastructure Engineering
C
20 85Monday, January 27, 2014 
Title 
Size Document Number Rev
Date: Sheet 
of 
Node1 CPU Power Rails 1A
Chassis Manager Assembly V1 
Cloud Server Infrastructure Engineering
C
20 85Monday, January 27, 2014 
C36 
1UF 16V 
10% 
C0603 
X7R 
C37 
0.1UF 
X7R 
16V 
10% 
C0402 
C38 
0.1UF 
X7R 
16V 
10% 
C0402 
C40 
0.1UF 
X7R 
16V 
10% 
C0402 
Processor 
U2G 
VCCDHPLL1P05 AD28 
VCCCPU0VIDSI01P05_1 U62 
VCCCPU0VIDSI01P05_2 U63 
VCCCPU0VIDSI01P05_3 U65 
VCCCPU0VIDSI01P05_4 V63 
VCCCPU0VIDSI01P05_5 V64 
VCCCPU0VIDSI01P05_6 V66 
VCCCPU0VIDSI01P05_7 W44 
VCCCPU0VIDSI01P05_8 W46 
VCCCPU0VIDSI01P05_9 W48 
VCCCPU0VIDSI01P05_10 W50 
VCCCPU0VIDSI01P05_11 W53 
VCCCPU0VIDSI01P05_12 W54 
VCCCPU0VIDSI01P05_13 W57 
VCCCPU0VIDSI01P05_14 W59 
VCCCPU0VIDSI01P05_15 Y48 
VCCCPU0VIDSI01P05_16 Y50 
VCCCPU0VIDSI01P05_17 Y53 
VCCCPU0VIDSI01P05_18 Y54 
VCCCPU0VIDSI01P05_19 Y57 
VCCCPU0VIDSI01P05_20 Y59 
VCCCPU0VIDSI01P05_21 AA44 
VCCCPU0VIDSI01P05_22 AA46 
VCCCPU0VIDSI01P05_23 AC44 
VCC_1 W32 
VCC_2 W36 
VCC_3 W39 
VCC_4 W42 
VCC_5 AA31 
VCC_6 AA34 
VCC_7 AA38 
VCC_8 AA41 
VCC_9 AC31 
VCC_10 AD29 
VCC_11 AD32 
VCC_12 AF31 
VCC_13 AG29 
VCC_14 AG32 
VCC_15 AG36 
VCC_16 AJ31 
VCC_17 AJ34 
VCC_18 AJ38 
VCC_19 AJ41 
VCC_20 AJ44 
VCC_21 AL29 
VCC_22 AL32 
VCC_23 AL36 
VCC_24 AL39 
VCC_25 AL42 
VCC_26 AM31 
VCC_27 AM34 
VCC_28 AM38 
VCC_29 AM41 
VCC_30 AP29 
VCC_31 AP32 
VCC_32 AT31 
VCC_33 AT34 
VCC_34 AU29 
VCC_35 AU32 
VCCA_DDR3_1P05_1 AP36 
VCCA_DDR3_1P05_2 AP38 
VCCA_DDR3_1P05_3 AP39 
VCCA_DDR3_1P05_4 AP41 
VCCA_DDR3_1P05_5 AP42 
VCCA_DDR3_1P05_6 AP44 
VCCA_DDR3_1P05_7 AP46 
VCCA_DDR3_1P05_8 AR48 
VCCA_DDR3_1P05_9 AR50 
VCCADLL_DDR3_1P05_1 AW46 
VCCADLL_DDR3_1P05_2 AW47 
VCCADLL_DDR3_1P05_3 AU36 
VCCADLL_DDR3_1P05_4 AU38 
VCCADLL_DDR3_1P05_5 AU39 
VCCADLL_DDR3_1P05_6 AU41 
VCCADLL_DDR3_1P05_7 AU42 
VCCADLL_DDR3_1P05_8 AU44 
VCCADLL_DDR3_1P05_9 AU46 
VCCADLL_DDR3_1P05_10 AU47 
VCCPLL_DDR3_1P05_1 AY38 
VCCPLL_DDR3_1P05_2 BA38 
VCCACLK_DDR3_1P05_1 AW32 
VCCACLK_DDR3_1P05_2 BA32 
VCCANTB_1P05_1 AC20 
VCCANTB_1P05_2 AC21 
VCCANTB_1P05_3 AC23 
VCCANTB_1P05_4 AC25 
VCCANTB_1P05_5 AC26 
VCCANTB_1P05_6 AL21 
VCCANTB_1P05_7 AL23 
VCCANTB_1P05_8 AL25 
VCCANTB_1P05_9 AL26 
VCCANTB_1P05_10 AL28 
VCCANTB_1P05_11 AP21 
VCCANTB_1P05_12 AP23 
VCCANTB_1P05_13 AP25 
VCCANTB_1P05_14 AP26 
VCCANTB_1P05_15 AP28 
VCCANTB_1P05_16 AU23 
VCCANTB_1P05_17 AU25 
VCCANTB_1P05_18 AU26 
VCCANTB_1P05_19 AU28 
VCCANTB_1P05_20 AW23 
VCCANTB_1P05_21 AC18 
VCCANTB_1P05_22 AD18 
VCCANTB_1P05_23 AD20 
VCCANTB_1P05_24 AL18 
VCCANTB_1P05_25 AL20 
VCCANTB_1P05_26 AP20 
VCCANTB_1P05_27 AR19 
VCCANTB_1P05_28 AW21 
VCCANTB_1P05_29 AY21 
VCCANTB_1P05_30 AY23 
VCCCPU0VIDSI0GT1P05_1 AC41 
VCCCPU0VIDSI0GT1P05_2 AC42 
VCCCPU1VIDSI0GT1P05_1 AG41 
VCCCPU1VIDSI0GT1P05_2 AG42 
VCCSUS1P05_1 P48 
VCCSUS1P05_2 T47 
VCCSUS1P05_3 T48 
Processor 
U2H 
VCCFHVCPU0SI01P05 AC36 
VCCFHVCPU1SI01P05 AF36 
VCCPLLCPU0SI01P05 AC49 
VCCPLLCPU1SI01P05 AD47 
VCCRAMCPU0XSI01P05_1 AC34 
VCCRAMCPU0XSI01P05_2 AG34 
VCC_DDR3_1P5_1 BD37 
VCC_DDR3_1P5_2 BD38 
VCC_DDR3_1P5_3 BD45 
VCC_DDR3_1P5_4 BE32 
VCC_DDR3_1P5_5 BE34 
VCC_DDR3_1P5_6 BE41 
VCC_DDR3_1P5_7 BE42 
VCC_DDR3_1P5_8 BK32 
VCC_DDR3_1P5_9 BK35 
VCC_DDR3_1P5_10 BK37 
VCC_DDR3_1P5_11 BK39 
VCC_DDR3_1P5_12 BK44 
VCC_DDR3_1P5_13 BK46 
VCC_DDR3_1P5_14 BM36 
VCC_DDR3_1P5_15 BM40 
VCC_DDR3_1P5_16 BM43 
VCC_DDR3_1P5_17 BM45 
VCC_DDR3_1P5_18 BM49 
VCC_DDR3_1P5_19 BP34 
VCCCLK_DDR3_1P5_1 BA41 
VCCCLK_DDR3_1P5_2 BB41 
VCCATS1P5 AF28 
VCCFHVSOC1P05_1 AL47 
VCCFHVSOC1P05_2 AL49 
VCCSFRPLL_DDR3_1P5_1 BA34 
VCCSFRPLL_DDR3_1P5_2 BB34 
TESTHI_1P5_01 AA28 
VCCREFRP0_1P5 AT28 
TESTHI_1P5_03 AM28 
TESTHI_1P5_05 AJ28 
TESTHI_1P5_00 AA21 
VCCARP0_1P5 AT21 
TESTHI_1P5_02 AM21 
TESTHI_1P5_04 AJ21 
VCCAGPIO1P8_1 L32 
VCCAGPIO1P8_2 N32 
VCCAGPIO1P8_3 P32 
VCCAGPIO1P8_4 T32 
VCCAGPIO1P8_5 V32 
VCCAGPIO1P8_6 AG28 
VCCSUS1P8_1 L41 
VCCSUS1P8_2 N41 
VCCSUS1P8_3 P41 
VCCASFRHPLL1P8_1 AD23 
VCCASFRHPLL1P8_2 AD25 
VCCABGTS1P8 AG23 
VCCAGPIO3P3_1 M37 
VCCAGPIO3P3_2 P37 
VCCAGPIO3P3_3 R37 
VCCAGPIO3P3_4 T36 
VCCAGPIO3P3_5 V36 
VCCAGPIO3P3_6 AF23 
VCCSUS3P3_1 L42 
VCCSUS3P3_2 N42 
VCCSUS3P3_3 P42 
VCCSUS3P3_4 T42 
VCCRTC3P3_1 M44 
VCCRTC3P3_2 P44 
VCCRTC3P3_3 R44 
VCCRTC3P3_4 T44 
R148 0 5% R0402 
C41 
0.1UF 
X7R 
16V 
10% 
C0402 
R150 0 5% R0402 
R149 0 5% R0402 
C35 2.2UF 
6.3V 
20% C0402 
X5R 
C39 
1UF 16V 
10% 
C0603 
X7R 



5
5
4
4
3
3
2
2
1
1
D D
C C
B B
A A
VSENSE_VCC_CPU_NODE1 (81) 
VSENSE_VSS_CPU_NODE1 (81) 
Title 
Size Document Number Rev
Date: Sheet 
of 
Node1 CPU GNDs 1A
Chassis Manager Assembly V1 
Cloud Server Infrastructure Engineering
C
21 85Monday, January 27, 2014 
Title 
Size Document Number Rev
Date: Sheet 
of 
Node1 CPU GNDs 1A
Chassis Manager Assembly V1 
Cloud Server Infrastructure Engineering
C
21 85Monday, January 27, 2014 
Title 
Size Document Number Rev
Date: Sheet 
of 
Node1 CPU GNDs 1A
Chassis Manager Assembly V1 
Cloud Server Infrastructure Engineering
C
21 85Monday, January 27, 2014 
Processor 
U2J 
VSS_161 U12 
VSS_162 V23 
VSS_163 V25 
VSS_164 V26 
VSS_165 V28 
VSS_166 V29 
VSS_167 V31 
VSS_168 V34 
VSS_169 V38 
VSS_170 V39 
VSS_171 V41 
VSS_172 V42 
VSS_173 V44 
VSS_174 V46 
VSS_175 W3 
VSS_176 W7 
VSS_177 W10 
VSS_178 W14 
VSS_179 W19 
VSS_180 W21 
VSS_181 W23 
VSS_182 W25 
VSS_183 W26 
VSS_184 W28 
VSS_185 W29 
VSS_186 W31 
VSS_187 W34 
VSS_188 W38 
VSS_189 W41 
VSS_190 W51 
VSS_191 W56 
VSS_192 W60 
VSS_193 W62 
VSS_194 Y4 
VSS_195 Y5 
VSS_196 Y7 
VSS_197 Y10 
VSS_198 Y14 
VSS_199 Y16 
VSS_200 Y17 
VSS_201 Y19 
VSS_202 Y51 
VSS_203 Y56 
VSS_204 Y60 
VSS_205 Y63 
VSS_206 Y65 
VSS_207 AA3 
VSS_208 AA5 
VSS_209 AA25 
VSS_210 AA26 
VSS_211 AA29 
VSS_212 AA32 
VSS_213 AA36 
VSS_214 AA39 
VSS_215 AA42 
VSS_216 AA47 
VSS_217 AB1 
VSS_218 AB20 
VSS_219 AB65 
VSS_220 AC8 
VSS_221 AC12 
VSS_222 AC17 
VSS_223 AC28 
VSS_224 AC29 
VSS_225 AC32 
VSS_226 AC39 
VSS_227 AC46 
VSS_228 AC50 
VSS_229 AC55 
VSS_230 AC59 
VSS_231 AD8 
VSS_232 AD12 
VSS_233 AD17 
VSS_234 AD21 
VSS_235 AD26 
VSS_236 AD31 
VSS_237 AD34 
VSS_238 AD36 
VSS_239 AD38 
VSS_240 AD42 
VSS_241 AD44 
VSS_242 AD46 
VSS_243 AD50 
VSS_244 AD55 
VSS_245 AD59 
VSS_246 AD65 
VSS_247 AD66 
VSS_248 AE1 
VSS_249 AE3 
VSS_250 AE5 
VSS_251 AE47 
VSS_252 AF20 
VSS_253 AF21 
VSS_254 AF25 
VSS_255 AF26 
VSS_256 AF29 
VSS_257 AF32 
VSS_258 AF34 
VSS_259 AF39 
VSS_260 AF42 
VSS_261 AF44 
VSS_262 AF46 
VSS_263 AF62 
VSS_264 AF65 
VSS_265 AG7 
VSS_266 AG11 
VSS_267 AG16 
VSS_268 AG17 
VSS_269 AG19 
VSS_270 AG21 
VSS_271 AG25 
VSS_272 AG26 
VSS_273 AG31 
VSS_274 AG38 
VSS_275 AG44 
VSS_276 AG46 
VSS_277 AG51 
VSS_278 AG56 
VSS_279 AM49 
VSS_280 AH7 
VSS_281 AH11 
VSS_282 AH16 
VSS_283 AH17 
VSS_284 AH19 
VSS_285 AH51 
VSS_286 AH56 
VSS_287 AH60 
VSS_288 AJ2 
VSS_289 AJ4 
VSS_290 AJ5 
VSS_291 AJ25 
VSS_292 AJ26 
VSS_293 AJ29 
VSS_294 AJ32 
VSS_295 AJ36 
VSS_296 AJ39 
VSS_297 AJ42 
VSS_298 AJ46 
VSS_299 AJ47 
VSS_300 AK20 
VSS_301 AK3 
VSS_302 AK5 
VSS_303 AK62 
VSS_304 AK64 
VSS_305 AK66 
VSS_306 AL1 
VSS_307 AL8 
VSS_308 AL12 
VSS_309 AL17 
VSS_310 AL31 
VSS_311 AL34 
VSS_312 AL38 
VSS_313 AL41 
VSS_314 AL44 
Processor 
U2L 
VSS_470 BD53 
VSS_471 BD54 
VSS_472 BD59 
VSS_473 BD62 
VSS_474 BE17 
VSS_475 BE19 
VSS_476 BE25 
VSS_477 BE50 
VSS_478 BE63 
VSS_479 BE66 
VSS_480 BF15 
VSS_481 BF23 
VSS_482 BF29 
VSS_483 BF30 
VSS_484 BF46 
VSS_485 BF53 
VSS_486 BF54 
VSS_487 BG4 
VSS_488 BG5 
VSS_489 BG11 
VSS_490 BG23 
VSS_491 BG26 
VSS_492 BG30 
VSS_493 BG46 
VSS_494 BG53 
VSS_495 BG54 
VSS_496 BG57 
VSS_497 BG63 
VSS_498 BH5 
VSS_499 BH11 
VSS_500 BH50 
VSS_501 BH60 
VSS_502 BH64 
VSS_503 BJ62 
VSS_504 BJ63 
VSS_505 BK6 
VSS_506 BK8 
VSS_507 BK10 
VSS_508 BK12 
VSS_509 BK13 
VSS_510 BK15 
VSS_511 BK17 
VSS_512 BK18 
VSS_513 BK19 
VSS_514 BK21 
VSS_515 BK22 
VSS_516 BK24 
VSS_517 BK26 
VSS_518 BK27 
VSS_519 BK28 
VSS_520 BK30 
VSS_521 BK31 
VSS_522 BK36 
VSS_523 BK42 
VSS_524 BK48 
VSS_525 BK53 
VSS_526 BK54 
VSS_527 BK56 
VSS_528 BK57 
VSS_529 BK58 
VSS_530 BK60 
VSS_531 BL8 
VSS_532 BL10 
VSS_533 BL12 
VSS_534 BL16 
VSS_535 BL21 
VSS_536 BL25 
VSS_537 BL30 
VSS_538 BL50 
VSS_539 BL52 
VSS_540 BL61 
VSS_541 BM61 
VSS_542 BN12 
VCCCPU0SENSE AD41 
VSSCPU0SENSE AF41 
VSS_543 BN21 
VSS_544 BN30 
VSS_545 BN50 
VSS_546 BP10 
VSS_547 BP16 
VSS_548 BP19 
VSS_549 BP25 
VSS_550 BP28 
VSS_551 BP52 
VSS_552 BP55 
VSS_553 BP58 
VSS_NCTF_1 A12 
VSS_NCTF_2 A5 
VSS_NCTF_3 A59 
VSS_NCTF_4 A6 
VSS_NCTF_5 A61 
VSS_NCTF_6 A62 
VSS_NCTF_7 A64 
VSS_NCTF_8 A66 
VSS_NCTF_9 A8 
VSS_NCTF_10 A9 
VSS_NCTF_11 C3 
VSS_NCTF_12 C5 
VSS_NCTF_13 C62 
VSS_NCTF_14 C64 
VSS_NCTF_15 C66 
VSS_NCTF_16 E1 
VSS_NCTF_17 E3 
VSS_NCTF_18 E5 
VSS_NCTF_19 E62 
VSS_NCTF_20 E64 
VSS_NCTF_21 E66 
VSS_NCTF_22 F66 
VSS_NCTF_23 H66 
VSS_NCTF_24 K1 
VSS_NCTF_25 N1 
VSS_NCTF_26 BG1 
VSS_NCTF_27 BG66 
VSS_NCTF_28 BJ1 
VSS_NCTF_29 BJ66 
VSS_NCTF_30 BK1 
VSS_NCTF_31 BK3 
VSS_NCTF_32 BK5 
VSS_NCTF_33 BK62 
VSS_NCTF_34 BK64 
VSS_NCTF_35 BK66 
VSS_NCTF_36 BM1 
VSS_NCTF_37 BM62 
VSS_NCTF_38 BM64 
VSS_NCTF_39 BM66 
VSS_NCTF_40 BP1 
VSS_NCTF_41 BP3 
VSS_NCTF_42 BP5 
VSS_NCTF_43 BP59 
VSS_NCTF_44 BP6 
VSS_NCTF_45 BP8 
VSS_NCTF_46 BP61 
VSS_NCTF_47 BP62 
VSS_NCTF_48 BP64 
VSS_NCTF_49 BP66 
Processor 
U2K 
VSS_315 AL46 
VSS_316 AL50 
VSS_317 AL55 
VSS_318 AL59 
VSS_319 AM8 
VSS_320 AM12 
VSS_321 AM17 
VSS_322 AM18 
VSS_323 AM20 
VSS_324 AM25 
VSS_325 AM26 
VSS_326 AM29 
VSS_327 AM32 
VSS_328 AM36 
VSS_329 AM39 
VSS_330 AM42 
VSS_331 AM44 
VSS_332 AM46 
VSS_333 AM50 
VSS_334 AM55 
VSS_335 AM59 
VSS_336 AN62 
VSS_337 AN66 
VSS_338 AP1 
VSS_339 AP3 
VSS_340 AP5 
VSS_341 AP31 
VSS_342 AP34 
VSS_343 AP62 
VSS_344 AR7 
VSS_345 AR11 
VSS_346 AR13 
VSS_347 AR17 
VSS_348 AT51 
VSS_349 AT56 
VSS_350 AR62 
VSS_351 AT7 
VSS_352 AT11 
VSS_353 AT16 
VSS_354 AT17 
VSS_355 AT19 
VSS_356 AT25 
VSS_357 AT26 
VSS_358 AT29 
VSS_359 AT32 
VSS_360 AT36 
VSS_361 AT38 
VSS_362 AT39 
VSS_363 AT41 
VSS_364 AT42 
VSS_365 AT44 
VSS_366 AT46 
VSS_367 AT48 
VSS_368 AT50 
VSS_369 AR51 
VSS_370 AR56 
VSS_371 AT66 
VSS_372 AU4 
VSS_373 AU21 
VSS_374 AU31 
VSS_375 AU34 
VSS_376 AU62 
VSS_377 AV4 
VSS_378 AV5 
VSS_379 AV63 
VSS_380 AV65 
VSS_381 AW3 
VSS_382 AW5 
VSS_383 AW8 
VSS_384 AW12 
VSS_385 AW17 
VSS_386 AW19 
VSS_387 AW20 
VSS_388 AW25 
VSS_389 AW26 
VSS_390 AW28 
VSS_391 AW30 
VSS_392 AW31 
VSS_393 AW34 
VSS_394 AW36 
VSS_395 AW38 
VSS_396 AW39 
VSS_397 AW41 
VSS_398 AW42 
VSS_399 AW44 
VSS_400 AW49 
VSS_401 AW50 
VSS_402 AW52 
VSS_403 AW53 
VSS_404 AW55 
VSS_405 AN47 
VSS_406 AM47 
VSS_407 AW59 
VSS_408 AW66 
VSS_409 AY1 
VSS_410 AY8 
VSS_411 AY12 
VSS_412 AY14 
VSS_413 AY15 
VSS_414 AY19 
VSS_415 AY29 
VSS_416 AY30 
VSS_417 AY37 
VSS_418 AY45 
VSS_419 AY46 
VSS_420 AY52 
VSS_421 AY53 
VSS_422 AY55 
VSS_423 AY56 
VSS_424 AY58 
VSS_425 AY59 
VSS_426 AY62 
VSS_427 BA17 
VSS_428 BA21 
VSS_429 BA23 
VSS_430 BA26 
VSS_431 BA30 
VSS_432 BA37 
VSS_433 BA42 
VSS_434 BA45 
VSS_435 BA46 
VSS_436 BA49 
VSS_437 BB32 
VSS_438 BB42 
VSS_439 BB50 
VSS_440 BB53 
VSS_441 BB54 
VSS_442 BB56 
VSS_443 BB62 
VSS_444 BB66 
VSS_445 BC1 
VSS_446 BC3 
VSS_447 BC5 
VSS_448 BC7 
VSS_449 BC11 
VSS_450 BC13 
VSS_451 BC15 
VSS_452 BC21 
VSS_453 BC23 
VSS_454 BC29 
VSS_455 BC30 
VSS_456 BC37 
VSS_457 BC45 
VSS_458 BC46 
VSS_459 BC62 
VSS_460 BD7 
VSS_461 BD15 
VSS_462 BD21 
VSS_463 BD23 
VSS_464 BD25 
VSS_465 BD29 
VSS_466 BD30 
VSS_467 BD32 
VSS_468 BD34 
VSS_469 BD46 
Processor 
U2I 
VSS_1 A15 
VSS_2 A18 
VSS_3 A21 
VSS_4 A24 
VSS_5 A27 
VSS_6 A30 
VSS_7 A33 
VSS_8 A36 
VSS_9 A39 
VSS_10 A42 
VSS_11 A45 
VSS_12 A54 
VSS_13 A57 
VSS_14 B14 
VSS_15 B23 
VSS_16 B32 
VSS_17 B37 
VSS_18 B46 
VSS_19 B50 
VSS_20 C6 
VSS_21 C9 
VSS_22 C13 
VSS_23 C18 
VSS_24 C22 
VSS_25 C27 
VSS_26 C54 
VSS_27 C58 
VSS_28 C60 
VSS_29 D6 
VSS_30 D8 
VSS_31 D14 
VSS_32 D32 
VSS_33 D37 
VSS_34 D39 
VSS_35 D41 
VSS_36 D46 
VSS_37 D50 
VSS_38 D59 
VSS_39 D60 
VSS_40 E7 
VSS_41 E9 
VSS_42 E13 
VSS_43 E14 
VSS_44 E16 
VSS_45 E18 
VSS_46 E22 
VSS_47 E25 
VSS_48 E27 
VSS_49 E30 
VSS_50 E32 
VSS_51 E34 
VSS_52 E37 
VSS_53 E41 
VSS_54 E43 
VSS_55 E45 
VSS_56 E46 
VSS_57 E50 
VSS_58 E54 
VSS_59 E58 
VSS_60 E61 
VSS_61 F4 
VSS_62 F63 
VSS_63 G3 
VSS_64 G7 
VSS_65 G10 
VSS_66 G48 
VSS_67 G50 
VSS_68 G56 
VSS_69 G59 
VSS_70 H4 
VSS_71 H21 
VSS_72 H22 
VSS_73 H29 
VSS_74 H44 
VSS_75 H58 
VSS_76 H62 
VSS_77 H63 
VSS_78 J5 
VSS_79 J29 
VSS_80 J52 
VSS_81 J54 
VSS_82 J66 
VSS_83 K17 
VSS_84 K18 
VSS_85 K25 
VSS_86 K26 
VSS_87 K32 
VSS_88 K34 
VSS_89 K41 
VSS_90 K42 
VSS_91 L5 
VSS_92 L7 
VSS_93 L8 
VSS_94 L13 
VSS_95 L14 
VSS_96 L29 
VSS_97 L30 
VSS_98 L34 
VSS_99 L37 
VSS_100 L38 
VSS_101 L44 
VSS_102 L46 
VSS_103 L48 
VSS_104 L50 
VSS_105 L57 
VSS_106 M3 
VSS_107 M5 
VSS_108 M21 
VSS_109 M22 
VSS_110 M29 
VSS_111 M30 
VSS_112 M57 
VSS_113 M62 
VSS_114 M64 
VSS_115 M66 
VSS_116 N7 
VSS_117 N11 
VSS_118 N34 
VSS_119 N63 
VSS_120 P17 
VSS_121 P18 
VSS_122 P25 
VSS_123 P26 
VSS_124 P29 
VSS_125 P30 
VSS_126 P38 
VSS_127 R8 
VSS_128 R12 
VSS_129 R29 
VSS_130 R30 
VSS_131 R38 
VSS_132 R46 
VSS_133 R52 
VSS_134 R53 
VSS_135 R55 
VSS_136 R59 
VSS_137 R66 
VSS_138 T1 
VSS_139 T3 
VSS_140 T5 
VSS_141 T17 
VSS_142 T20 
VSS_143 T21 
VSS_144 T23 
VSS_145 T25 
VSS_146 T26 
VSS_147 T28 
VSS_148 T29 
VSS_149 T31 
VSS_150 T34 
VSS_151 T37 
VSS_152 T39 
VSS_153 T41 
VSS_154 T45 
VSS_155 T50 
VSS_156 T55 
VSS_157 T59 
VSS_158 T62 
VSS_159 T64 
VSS_160 U8 



5
5
4
4
3
3
2
2
1
1
D D
C C
B B
A A
PUNIT START ADDRESS 
PUNIT_ST_ADDR<1:0> 
*[00] 0XFFFB_0000 (DEFAULT) 
[01] 0XFFFC_0000 
[1X] 0XFFFD_0000 
HVMGEAR_SEL 
*0 = DISABLED; GEARING SET BY FUSES 
1 = ENABLED; GEARING IS FORCED 
BOOTDEVSEL: 
*0 - BOOT FROM SPI 
1 - BOOT FROM LPC 
BOARD IDS: 
NODE ID: 
0 - NODE1 
1- NODE 2 
SPED_ENB 
*0: SPD ENABLED, SPD EXPECTED, DIMMS 
1: SPD DISABLED, SDRAM DOWN 
DRAM SPEED (NO SPD CASE) 
MEMSPEED<1:0> 
00:DDR3-1066 
*01:DDR3-1333 DEFAULT 
10:DDR3-1600 
11:RESERVE 
PD_CPU_NODE1_BRD_ID1 (16) PU_CPU_NODE1_BRD_ID0 (16) 
VR_CPU_NODE1_INTVRMEN (16) 
PD_CPU_NODE1_NODE_ID (16) 
RST_CPU_NODE1_SRTCRST_L (16) 
LPC_CPU_NODE1_CLK0_DS (16) 
PD_CPU_NODE1_BOOTDEVSEL (16) 
PD_CPU_NODE1_MEM_SPEED1 (19) 
PD_CPU_NODE1_SPD_EN_L (19) 
PU_CPU_NODE1_MEM_SPEED0 (19) 
PD_CPU_NODE1_PUNIT_ST_ADDR0 (19) 
PD_CPU_NODE1_HVMGEAR_SEL (19) 
PD_CPU_NODE1_PUNIT_ST_ADDR1 (19) 
P3V3_NODE1 
P3V3_NODE1 
P3V3_NODE1 
P3V3_RTC_NODE1 
P3V3_RTC_NODE1 
P3V3_NODE1 
P3V3_NODE1 
P1V05_SUS_NODE1 
P1V05_SUS_NODE1 
P1V05_SUS_NODE1 
P1V05_SUS_NODE1 
P1V05_SUS_NODE1 
P1V05_SUS_NODE1 
Title 
Size Document Number Rev
Date: Sheet 
of 
Node1 CPU Strapping 1A
Chassis Manager Assembly V1 
Cloud Server Infrastructure Engineering
C
22 85Monday, January 27, 2014 
Title 
Size Document Number Rev
Date: Sheet 
of 
Node1 CPU Strapping 1A
Chassis Manager Assembly V1 
Cloud Server Infrastructure Engineering
C
22 85Monday, January 27, 2014 
Title 
Size Document Number Rev
Date: Sheet 
of 
Node1 CPU Strapping 1A
Chassis Manager Assembly V1 
Cloud Server Infrastructure Engineering
C
22 85Monday, January 27, 2014 
R163 
4.7K 
5% 
R0402 
R153 
10K 
1% 
R0402 
R172 
10K 
1% 
R0402 
NI 
R151 
10K 
1% 
R0402 
NI 
R169 
10K 
1% 
R0402 
R176 
1K 
1% 
R0402 
NI 
R152 
10K 
1% 
R0402 
NI 
R158 
10K 
1% 
R0402 
NI 
R173 
0
5% 
R0402 
NI 
R156 
330 
5% 
R0402 
NI 
R167 
0
5% 
R0402 
R171 
10K 
1% 
R0402 
R175 
4.7K 
5% 
R0402 
R166 
1K 
1% 
R0402 
NI 
R157 
10K 
1% 
R0402 
NI 
R165 
10K 
1% 
R0402 
NI 
R160 
1K 
1% 
R0402 
R159 
10K 
1% 
R0402 
NI 
R170 
1K 
1% 
R0402 
NI 
R164 
10K 
1% 
R0402 
NI 
R155 
330 
5% 
R0402 
R174 
0
5% 
R0402 
R154 
1K 
1% 
R0402 
R168 
0
5% 
R0402 
R161 
0
5% 
R0402 
R162 
0
5% 
R0402 



5
5
4
4
3
3
2
2
1
1
D D
C C
B B
A A
TPM 
CAD Note: 
THIS PART WILL CO-LAY WITH SOCKET 
USE ALT SYMBOL ASSOCIATED WITH SOCKET FOOTPRINT 
SPI FLASH 
7 56 2 04 1 3
LED placement 
Port 80 
SPI_CPU_NODE1_MISO_R 
SPI_CPU_NODE1_HOLD_L 
SPI_CPU_NODE1_WP_L 
SPI_CPU_NODE1_SCLK 
SPI_CPU_NODE1_SCLK 
SPI_CPU_NODE1_CS0_L 
SPI_CPU_NODE1_MOSI 
SPI_CPU_NODE1_CS0_L 
IRQ_CPU_NODE1_SERIAL 
TP_P3V3_NODE1_INIT_L 
TP_BIOS_NODE1_PORT80_ID0 
TPM_LPC_SERIRQ_PORT80_NODE1 
SPI_CPU_NODE1_HOLD_L 
SPI_CPU_NODE1_WP_L 
SPI_CPU_NODE1_MOSI 
SPI_CPU_NODE1_MISO SPI_CPU_NODE1_MISO_R 
SPI_CPU_NODE1_MISO_R 
PORT80_LOUT6 
PORT80_LOUT5 
LPC_CPU_NODE1_LAD2 
PORT80_LOUT3 
LPC_CPU_NODE1_LAD1 LPC_CPU_NODE1_LAD0 
PORT80_LOUT2 
LPC_CPU_NODE1_LAD3 
LPC_CPU_NODE1_FRAME_L 
PORT80_LOUT0 
PORT80_LOUT4 
PORT80_LOUT7 
PORT80_LOUT1 
PORT80_LOUT1 
PORT80_LOUT2 
PORT80_LOUT3 
PORT80_LOUT4 
PORT80_LOUT5 
PORT80_LOUT6 
PORT80_LOUT7 
PORT80_LOUT0 
LPC_CPU_TPM_LAD0 
LPC_CPU_TPM_LAD1 
LPC_CPU_TPM_LAD2 
LPC_CPU_TPM_LAD3 
SPI_CPU_NODE1_CS0_L (16) 
SPI_CPU_NODE1_SCLK (16) 
SPI_CPU_NODE1_MOSI (16) 
SPI_CPU_NODE1_WP_L (16) 
LPC_CPU_NODE1_FRAME_L (16) 
LPC_CPU_NODE1_CLKOUT0 (16) 
FM_CPLD_NODE1_LPCRST_L (67) 
IRQ_CPU_NODE1_SERIAL (16,52) 
SPI_CPU_NODE1_WP_L (16) 
SPI_CPU_NODE1_CS0_L (16) 
SPI_CPU_NODE1_SCLK (16) 
SPI_CPU_NODE1_MOSI (16) 
SPI_CPU_NODE1_MISO (16) 
CLK_33M_PORT80 (13) 
LPC_CPU_NODE1_LAD2 (16,52) 
LPC_CPU_NODE1_LAD3 (16,52) 
LPC_CPU_NODE1_LAD0 (16,52) 
LPC_CPU_NODE1_LAD1 (16,52) 
FM_CPLD_NODE1_LPCRST_L 
P3V3_NODE1 
P3V3_NODE1 
P5V_NODE1 
P3V3_NODE1 
P3V3_NODE1 
P3V3_NODE1 
P5V_NODE1 
P3V3_NODE1 
P3V3_NODE1 
P3V3_NODE1 
P3V3_NODE1 
P3V3_NODE1 
Title 
Size Document Number Rev
Date: Sheet 
of 
Node1 CPU SPI & 80 Port & TPM 1A
Chassis Manager Assembly V1 
Cloud Server Infrastructure Engineering
C
23 85Monday, January 27, 2014 
Title 
Size Document Number Rev
Date: Sheet 
of 
Node1 CPU SPI & 80 Port & TPM 1A
Chassis Manager Assembly V1 
Cloud Server Infrastructure Engineering
C
23 85Monday, January 27, 2014 
Title 
Size Document Number Rev
Date: Sheet 
of 
Node1 CPU SPI & 80 Port & TPM 1A
Chassis Manager Assembly V1 
Cloud Server Infrastructure Engineering
C
23 85Monday, January 27, 2014 
D31 AC
R1257 150 
C1120 0.1UF 
R177 4.7K 
R0402 5% 
R1260 150 
R1258 150 
R179 0
5% R0402 
R1259 150 
U115 
LC4032-75T48C 
GND 37 
B12 38 
B13 39 
B14 40 
B15/GOE1 41 
CLK3/I 42 
CLK0/I 43 
A0/GOE0 44 
A1 45 
A2 46 
A3 47 
A4 48 
TDI 1
A5 2
A6 3
A7 4
GND(BANK0) 5
VCCO(BANK0) 6
A8 7
A9 8
A10 9
A11 10 
TCK 11 
VCC 12 
GND 13 A12 14 A13 15 A14 16 A15 17 CLK1/I 18 CLK2/I 19 B0 20 B1 21 B2 22 B3 23 B4 24 
TMS 25 B5 26 B6 27 B7 28 GND(BANK1) 29 VCCO(BANK1) 30 B8 31 B9 32 B10 33 B11 34 TDO 35 VCC 36 
R189 51 R0402 1% 
R194 51 R0402 1% 
R193 0 R0402 5% 
D32 AC
J1 
HEADER 2X7 
1 2
3 4
6
11 
8
9 10 
7
12 
13 14 
5R190 51 R0402 1% 
TP175 1
TP172 
1
D36 AC
R191 51 R0402 1% 
C1119 0.1UF 
U4 
W25Q64FVSSIG 
CS 1
SO 2 WP 3
Vss 4SI 5 SCK 6 HOLD 7Vcc 8
D33 AC
R192 51 R0402 1% 
C42 0.1UF 
X7R 16V 
C0402 10% 
C134 
0.1UF 
X7R 
16V 
C0402 
10% 
D37 AC
C1121 
0.1UF 
D34 AC
R178 15 
R0402 5% 
R1253 150 
TP173 
1
C135 
0.1UF 
X7R 
16V 
C0402 
10% 
TP174 1
R1254 150 
D38 AC
D35 AC
R1255 150 
U5 
SOCKET8P 
CS 1
SO 2 WP 3
Vss 4SI 5 SCK 6 HOLD 7Vcc 8
C1122 
0.1UF 
R1256 150 



5
5
4
4
3
3
2
2
1
1
D D
C C
B B
A A
VCCAGPIO1P8 
VCCA_DDR3_1P05 
P1V05_NODE1 
PV_VCCP_NODE1 
PV_VCCP_NODE1 
P1V05_NODE1 
PV_VDDR_NODE1 
P1V05_NODE1 
P1V8_SUS_NODE1 P1V8_SUS_NODE1 
P1V8_NODE1 
P3V3_SUS_NODE1 
P1V05_NODE1 
P1V05_NODE1 P1V05_VCCACLK_DDR3_NODE1 
PV_VDDR_NODE1 
PV_VDDR_VCCCLK_DDR3_NODE1
P1V05_NODE1 P1V05_VCCPLL_DDR3_NODE1 
P1V5_SUS_NODE1 P1V5_SFRPLL_NODE1 
P1V8_NODE1 P1V8_VCCASFRHPLL_NODE1 
P1V05_NODE1 P1V05_VCCPLLCPU0SIO_NODE1
P1V05_NODE1 P1V05_VCCPLLCPU1SIO_NODE1
Title 
Size Document Number Rev
Date: Sheet 
of 
Node1 CPU Decoupling 1A
Chassis Manager Assembly V1 
Cloud Server Infrastructure Engineering
C
24 85Monday, January 27, 2014 
Title 
Size Document Number Rev
Date: Sheet 
of 
Node1 CPU Decoupling 1A
Chassis Manager Assembly V1 
Cloud Server Infrastructure Engineering
C
24 85Monday, January 27, 2014 
Title 
Size Document Number Rev
Date: Sheet 
of 
Node1 CPU Decoupling 1A
Chassis Manager Assembly V1 
Cloud Server Infrastructure Engineering
C
24 85Monday, January 27, 2014 
C60 
10UF 10V 
20% 
X5R 
C0603 
C87 
1UF 10V 
10% 
C0402 
X5R 
C47 
2.2UF 6.3V 
20% 
C0402 
X5R 
C111 
10UF 10V 
20% 
X5R 
C0603 
C106 
2.2UF 6.3V 
20% 
C0402 
X5R 
C75 
10UF 10V 
20% 
X5R 
C0603 
C85 
1UF 10V 
10% 
C0402 
X5R 
C55 
22UF 
20% 
6.3V 
X5R 
C0805_H61 
C52 
2.2UF 6.3V 
20% 
C0402 
X5R 
C118 
2.2UF 
20% 
6.3V 
C0402 
X5R 
C107 
2.2UF 6.3V 
20% 
C0402 
X5R 
C95 
1UF 10V 
10% 
C0402 
X5R 
C89 
1UF 10V 
10% 
C0402 
X5R 
C92 
10UF 10V 
20% 
X5R 
C0603 
C116 
2.2UF 
20% 
6.3V 
C0402 
X5R 
C132 
1UF 10V 
10% 
C0402 
X5R 
C76 
1UF 10V 
10% 
C0402 
X5R 
C64 
1UF 10V 
10% 
C0402 
X5R 
C44 
2.2UF 6.3V 
20% 
C0402 
X5R 
C50 
2.2UF 6.3V 
20% 
C0402 
X5R 
C120 
1UF 10V 
10% 
C0402 
X5R 
C56 
2.2UF 6.3V 
20% 
C0402 
X5R 
C93 
10UF 10V 
20% 
X5R 
C0603 
C59 
2.2UF 6.3V 
20% 
C0402 
X5R 
C88 
1UF 10V 
10% 
C0402 
X5R 
C130 
2.2UF 6.3V 
20% 
C0402 
X5R 
C79 
1UF 10V 
10% 
C0402 
X5R 
C96 
47UF 4V 
20% 
C1206_H76 
X6S 
C84 
1UF 10V 
10% 
C0402 
X5R 
C77 
1UF 10V 
10% 
C0402 
X5R 
C117 
2.2UF 
20% 
6.3V 
C0402 
X5R 
C61 
1UF 10V 
10% 
C0402 
X5R 
C126 
2.2UF 6.3V 
20% 
C0402 
X5R 
C90 
1UF 10V 
10% 
C0402 
X5R 
L5 
120/0.3A 
L0402 
21
C81 
1UF 10V 
10% 
C0402 
X5R 
C48 
2.2UF 6.3V 
20% 
C0402 
X5R 
C91 
10UF 10V 
20% 
X5R 
C0603 
C78 
10UF 10V 
20% 
X5R 
C0603 
C86 
1UF 10V 
10% 
C0402 
X5R 
L6 
120/0.3A 
L0402 
21
C100 
2.2UF 6.3V 
20% 
C0402 
X5R 
C105 
2.2UF 6.3V 
20% 
C0402 
X5R 
L9 
120/0.3A 
L0402 
21
C115 
2.2UF 
20% 
6.3V 
C0402 
X5R 
C66 
1UF 10V 
10% 
C0402 
X5R 
C99 
2.2UF 6.3V 
20% 
C0402 
X5R 
C110 
10UF 10V 
20% 
X5R 
C0603 
C65 
1UF 10V 
10% 
C0402 
X5R 
L4 
120/0.3A 
L0402 
21
C114 
2.2UF 
20% 
6.3V 
C0402 
X5R 
C94 
1UF 10V 
10% 
C0402 
X5R 
C69 
1UF 10V 
10% 
C0402 
X5R 
C57 
2.2UF 6.3V 
20% 
C0402 
X5R 
C97 
22UF 
20% 
6.3V 
X5R 
C0805_H61 
C128 
2.2UF 6.3V 
20% 
C0402 
X5R 
C54 
22UF 
20% 
6.3V 
X5R 
C0805_H61 
C58 
2.2UF 6.3V 
20% 
C0402 
X5R 
C101 
2.2UF 6.3V 
20% 
C0402 
X5R 
C109 
10UF 10V 
20% 
X5R 
C0603 
C62 
2.2UF 6.3V 
20% 
C0402 
X5R 
C104 
2.2UF 6.3V 
20% 
C0402 
X5R 
C121 
2.2UF 6.3V 
20% 
C0402 
X5R 
C80 
2.2UF 6.3V 
20% 
C0402 
X5R 
C123 
2.2UF 6.3V 
20% 
C0402 
X5R 
C102 
2.2UF 6.3V 
20% 
C0402 
X5R 
C103 
2.2UF 6.3V 
20% 
C0402 
X5R 
C74 
10UF 10V 
20% 
X5R 
C0603 
C113 
10UF 10V 
10% 
X7R 
C0805_H61 
C73 
1UF 10V 
10% 
C0402 
X5R 
C125 
2.2UF 6.3V 
20% 
C0402 
X5R 
C53 
22UF 
20% 
6.3V 
X5R 
C0805_H61 
L7 
120/0.3A 
L0402 
21
C98 
2.2UF 6.3V 
20% 
C0402 
X5R 
C63 
22UF 
20% 
6.3V 
X5R 
C0805_H61 
C119 
2.2UF 
20% 
6.3V 
C0402 
X5R 
L8 
120/0.3A 
L0402 
21
C49 
2.2UF 6.3V 
20% 
C0402 
X5R 
C45 
2.2UF 6.3V 
20% 
C0402 
X5R 
C83 
1UF 10V 
10% 
C0402 
X5R 
L10 
120/0.3A 
L0402 
21
C108 
10UF 10V 
20% 
X5R 
C0603 
C51 
2.2UF 6.3V 
20% 
C0402 
X5R 
C71 
1UF 10V 
10% 
C0402 
X5R 
C67 
1UF 10V 
10% 
C0402 
X5R 
C129 
2.2UF 6.3V 
20% 
C0402 
X5R 
C72 
1UF 10V 
10% 
C0402 
X5R 
C112 
1UF 10V 
10% 
C0402 
X5R 
C127 
2.2UF 6.3V 
20% 
C0402 
X5R 
C46 
2.2UF 6.3V 
20% 
C0402 
X5R 
C131 
2.2UF 
20% 
6.3V 
C0402 
X5R 
C82 
1UF 10V 
10% 
C0402 
X5R 
C68 
1UF 10V 
10% 
C0402 
X5R 
C122 
2.2UF 6.3V 
20% 
C0402 
X5R 
C124 
2.2UF 6.3V 
20% 
C0402 
X5R 
C70 
1UF 10V 
10% 
C0402 
X5R 
C43 
2.2UF 6.3V 
20% 
C0402 
X5R 



5
5
4
4
3
3
2
2
1
1
D D
C C
B B
A A
Title 
Size Document Number Rev
Date: Sheet 
of 
Blank 1A
Chassis Manager Assembly V1 
Cloud Server Infrastructure Engineering
C
25 85Monday, January 27, 2014 
Title 
Size Document Number Rev
Date: Sheet 
of 
Blank 1A
Chassis Manager Assembly V1 
Cloud Server Infrastructure Engineering
C
25 85Monday, January 27, 2014 
Title 
Size Document Number Rev
Date: Sheet 
of 
Blank 1A
Chassis Manager Assembly V1 
Cloud Server Infrastructure Engineering
C
25 85Monday, January 27, 2014 



5
5
4
4
3
3
2
2
1
1
D D
C C
B B
A A
SMBus (8-bit) Address:0x90 
SMB_TEMP1_NODE1_ALERT_R_L 
PU_EMC1428_NODE1_TRIP 
TP_TEMP1_NODE1_2 
TP_TEMP1_NODE1_3 
TP_TEMP1_NODE1_1 
PU_TEMP1_NODE1_SYS_SHDN_L 
A_CPU0_NODE1_THERMDA (18) 
A_CPU0_NODE1_THERMDC (18) 
SMB_TEMP1_NODE1_ALERT_L (16) 
SMB_MUX_CPU_ICS_NODE1_CLK (13,18) 
SMB_MUX_CPU_ICS_NODE1_DAT (13,18,27) 
A_CPU1_NODE1_THERMDA (18) 
A_CPU1_NODE1_THERMDC (18) 
A_SOC_NODE1_THERMDA (18) 
A_SOC_NODE1_THERMDC (18) 
P3V3_NODE1 
P3V3_NODE1 
Title 
Size Document Number Rev
Date: Sheet 
of 
Node1 CPU Temperature ADC 1A
Chassis Manager Assembly V1 
Cloud Server Infrastructure Engineering
C
26 85Monday, January 27, 2014 
Title 
Size Document Number Rev
Date: Sheet 
of 
Node1 CPU Temperature ADC 1A
Chassis Manager Assembly V1 
Cloud Server Infrastructure Engineering
C
26 85Monday, January 27, 2014 
Title 
Size Document Number Rev
Date: Sheet 
of 
Node1 CPU Temperature ADC 1A
Chassis Manager Assembly V1 
Cloud Server Infrastructure Engineering
C
26 85Monday, January 27, 2014 
U9 
EMC1428-7-AP-TR 
VDD 16 
DP1 1
DN1 2
DP2/DN3 3
DN2/DP3 4
DP4/DN5 10 
DN4/DP5 9
DP6/DN7 15 
DN6/DP7 14 
TRIP_SET 5
SYS_SHDN# 6
ALERT# 7
SMDATA 11 
SMCLK 12 
NC#13 13 
GND8 8
TH_PAD TH 
R196 
4.7K R0402 
5% 
C137 
180PF 5% 
C0402 
50V 
NPO 
R199 0
5% R0402 
R197 
4.7K R0402 
5% 
C138 
180PF 5% 
C0402 
50V 
NPO 
C136 
0.1UF 
X7R 
16V 
C0402 
10% 
C139 
180PF 5% 
C0402 
50V 
NPO 
R198 
4.7K R0402 
5% 



5
5
4
4
3
3
2
2
1
1
D D
C C
B B
A A
CLOSE TO PIN 
PD_NODE1_DM7 
TP_DDR3_NODE1_CS3_L 
TP_DDR3_NODE1_CS2_L 
PD_NODE1_DM5 
PD_NODE1_DM6 
P1V5_NODE1_DDR3_VREF0_D 
PD_NODE1_DM4 
P1V5_NODE1_DDR3_VREF_A_A 
PD_NODE1_DM3 
PD_NODE1_DM1 
PD_NODE1_DM2 
PD_NODE1_DM0 
P1V5_NODE1_DDR3_VREF_A_A 
PD_NODE1_DM8 
TP_NODE1_ERR_OUT_DIMM0 
PV_VDDR_NODE1_VREF_RW 
PV_VDDR_NODE1_VREF_R P1V5_NODE1_DDR3_VREF0_D PV_VDDR_NODE1_VREF_LM321 
P1V5_NODE1_DDR3_VREF0_D 
SMB_MUX_CPU_ICS_NODE1_DAT SMB_DIMM_NODE1_DAT 
SMB_MUX_CPU_ICS_NODE1_CLK SMB_DIMM_NODE1_CLK 
M1_DQ_NODE1_DQ47 (14) 
M1_DQ_NODE1_DQ44 (14) 
M1_DQ_NODE1_DQ43 (14) 
M1_DQ_NODE1_DQ46 (14) 
M1_DQ_NODE1_DQ45 (14) 
M1_DQ_NODE1_DQ48 (14) 
M1_DQ_NODE1_DQ42 (14) 
M1_DQ_NODE1_DQ40 (14) 
M1_DQ_NODE1_DQ55 (14) 
M1_DQ_NODE1_DQ52 (14) 
M1_DQ_NODE1_DQ51 (14) 
M1_DQ_NODE1_DQ54 (14) 
M1_DQ_NODE1_DQ53 (14) 
M1_DQ_NODE1_DQ56 (14) 
M1_DQ_NODE1_DQ60 (14) 
M1_DQ_NODE1_DQ59 (14) 
M1_DQ_NODE1_DQ61 (14) 
M1_DQ_NODE1_DQ63 (14) 
M1_DQ_NODE1_DQ58 (14) 
M1_DQ_NODE1_DQ57 (14) 
M1_DQ_NODE1_DQ62 (14) 
M1_DQ_NODE1_DQ50 (14) 
M1_DQ_NODE1_DQ49 (14) 
M1_DQ_NODE1_DQ41 (14) 
M1_DQ_NODE1_DQ1 (14) 
M1_DQ_NODE1_DQ0 (14) 
M1_DQ_NODE1_DQ3 (14) 
M1_DQ_NODE1_DQ2 (14) 
M1_DQ_NODE1_DQ38 (14) 
M1_DQ_NODE1_DQ35 (14) 
M1_DQ_NODE1_DQ34 (14) 
M1_DQ_NODE1_DQ37 (14) 
M1_DQ_NODE1_DQ36 (14) 
M1_DQ_NODE1_DQ39 (14) 
M1_DQ_NODE1_DQ6 (14) 
M1_DQ_NODE1_DQ33 (14) 
M1_DQ_NODE1_DQ32 (14) 
M1_DQ_NODE1_DQ5 (14) 
M1_DQ_NODE1_DQ4 (14) 
M1_DQ_NODE1_DQ7 (14) 
M1_DQ_NODE1_DQ11 (14) 
M1_DQ_NODE1_DQ10 (14) 
M1_DQ_NODE1_DQ12 (14) 
M1_DQ_NODE1_DQ15 (14) 
M1_DQ_NODE1_DQ14 (14) 
M1_DQ_NODE1_DQ9 (14) 
M1_DQ_NODE1_DQ8 (14) 
M1_DQ_NODE1_DQ13 (14) 
M1_DQ_NODE1_DQ19 (14) 
M1_DQ_NODE1_DQ18 (14) 
M1_DQ_NODE1_DQ20 (14) 
M1_DQ_NODE1_DQ23 (14) 
M1_DQ_NODE1_DQ22 (14) 
M1_DQ_NODE1_DQ26 (14) 
M1_DQ_NODE1_DQ21 (14) 
M1_DQ_NODE1_DQ31 (14) 
M1_DQ_NODE1_DQ30 (14) 
M1_DQ_NODE1_DQ27 (14) 
M1_DQ_NODE1_DQ24 (14) 
M1_DQ_NODE1_DQ29 (14) 
M1_DQ_NODE1_DQ28 (14) 
M1_DQ_NODE1_DQ16 (14) 
M1_DQ_NODE1_DQ25 (14) 
M1_DQ_NODE1_DQ17 (14) 
M_DDR3_NODE1_MA0 (14) 
M_DDR3_NODE1_MA1 (14) 
M_DDR3_NODE1_MA2 (14) 
M_DDR3_NODE1_MA3 (14) 
M_DDR3_NODE1_MA4 (14) 
M_DDR3_NODE1_MA5 (14) 
M_DDR3_NODE1_MA6 (14) 
M_DDR3_NODE1_MA7 (14) 
M_DDR3_NODE1_MA8 (14) 
M_DDR3_NODE1_MA9 (14) 
M_DDR3_NODE1_MA10 (14) 
M_DDR3_NODE1_MA11 (14) 
M_DDR3_NODE1_MA12 (14) 
M_DDR3_NODE1_MA13 (14) 
M_DDR3_NODE1_MA14 (14) 
M_DDR3_NODE1_MA15 (14) 
M_DDR3_NODE1_BS0 (14) 
M_DDR3_NODE1_BS2 (14) 
M_DDR3_NODE1_BS1 (14) 
M_DDR3_NODE1_ECC7 (14) 
M_DDR3_NODE1_ECC6 (14) 
M_DDR3_NODE1_ECC5 (14) 
M_DDR3_NODE1_ECC4 (14) 
M_DDR3_NODE1_ECC3 (14) 
M_DDR3_NODE1_ECC2 (14) 
M_DDR3_NODE1_ECC1 (14) 
M_DDR3_NODE1_ECC0 (14) 
M_DDR3_NODE1_CK1N (14) 
M_DDR3_NODE1_CK0N (14) 
M_DDR3_NODE1_CK1P (14) 
M_DDR3_NODE1_CK0P (14) 
M_DDR3_NODE1_CKE1 (14) 
M_DDR3_NODE1_CKE0 (14) 
M_DDR3_NODE1_ODT1 (14) 
M_DDR3_NODE1_ODT0 (14) 
M_DDR3_NODE1_CS1_L (14) 
M_DDR3_NODE1_CS0_L (14) 
M_DDR3_NODE1_RAS_L (14) 
M_DDR3_NODE1_CAS_L (14) 
M_DDR3_NODE1_WE_L (14) 
M_NODE1_DIMM_RST_L (14) 
SMB_DIMM_NODE1_CLK 
SMB_DIMM_NODE1_DAT 
M_DDR3_NODE1_DQS0P (14) 
M_DDR3_NODE1_DQS1P (14) 
M_DDR3_NODE1_DQS2P (14) 
M_DDR3_NODE1_DQS3P (14) 
M_DDR3_NODE1_DQS6P (14) 
M_DDR3_NODE1_DQS7P (14) 
M_DDR3_NODE1_DQS4P (14) 
M_DDR3_NODE1_DQS5P (14) 
M_DDR3_NODE1_DQS2N (14) 
M_DDR3_NODE1_DQS3N (14) 
M_DDR3_NODE1_DQS6N (14) 
M_DDR3_NODE1_DQS7N (14) 
M_DDR3_NODE1_DQS4N (14) 
M_DDR3_NODE1_DQS5N (14) 
M_DDR3_NODE1_DQS0N (14) 
M_DDR3_NODE1_DQS1N (14) 
M_DDR3_NODE1_DQSECCN (14) 
M_DDR3_NODE1_DQSECCP (14) 
SMB_MUX_CPU_ICS_NODE1_CLK (13,18) 
SMB_MUX_CPU_ICS_NODE1_DAT (13,18,26) 
SMB_MUX_CPU_ICS_NODE1_CLK (13,18) 
SMB_MUX_CPU_ICS_NODE1_DAT (13,18,26) 
PV_VDDR_NODE1 
PV_VDDR_NODE1 
P3V3_NODE1 
PV_VTT_DDR_NODE1 
PV_VDDR_NODE1 
PV_VDDR_NODE1 
PV_VDDR_NODE1 
P5V_STB_NODE1 
PV_VDDR_NODE1 
PV_VDDR_NODE1 
P3V3_STB_NODE1 
Title 
Size Document Number Rev
Date: Sheet 
of 
Node1 SO-DIMM DIMM 1A
Chassis Manager Assembly V1 
Cloud Server Infrastructure Engineering
C
27 85Monday, January 27, 2014 
Title 
Size Document Number Rev
Date: Sheet 
of 
Node1 SO-DIMM DIMM 1A
Chassis Manager Assembly V1 
Cloud Server Infrastructure Engineering
C
27 85Monday, January 27, 2014 
Title 
Size Document Number Rev
Date: Sheet 
of 
Node1 SO-DIMM DIMM 1A
Chassis Manager Assembly V1 
Cloud Server Infrastructure Engineering
C
27 85Monday, January 27, 2014 
C173 
1000PF 
C0603 
10% 
50V 
NPO 
C172 
1000PF 
C0603 
10% 
50V 
NPO 
C147 
0.1UF 
X7R 
16V 
C0402 
10% 
C145 
0.1UF 
X7R 
16V 
C0402 
10% 
C169 
0.1UF 
X7R 
16V 
C0402 
10% 
C179 
0.1UF 
X7R 
16V 
C0402 
10% 
C149 
0.1UF 
X7R 
16V 
C0402 
10% 
R208 0 5% R0402 
C167 
0.1UF 
X7R 
16V 
C0402 
10% 
R207 0 5% R0402 
C152 
0.1UF 
X7R 
16V 
C0402 
10% 
R205 0 5% R0402 
R217 0
5% R0402 
R211 0 5% R0402 
C170 
0.1UF 
X7R 
16V 
C0402 
10% 
SCONN204_AS0A621HASN7H 
J2B 
VDD13 85 
VDD12 86 
VDD11 93 
VDD10 94 
VDD9 101 
VDD8 102 
VDD7 109 
VDD6 110 
VDD5 115 
VDD4 116 
VDD3 123 
VDD2 124 
VDD1 131 
VDD0 132 
VDDSPD 199 
VTT1 203 
VTT0 204 
VREF_CA 84 
VREF_DQ 1
GND45 2
GND44 3
GND43 8
GND42 9
GND41 14 
GND40 17 
GND39 20 
GND38 23 
GND37 26 
GND36 29 
GND35 32 
GND34 35 
GND33 38 
GND32 41 
GND31 46 
GND30 47 
GND29 52 
GND28 53 
GND27 58 
GND26 61 
GND25 64 
GND24 67 
GND23 70 
GND22 73 
GND21 78 
GND20 79 
GND19 137 
GND18 138 
GND17 143 
GND16 146 
GND15 149 
GND14 152 
GND13 155 
GND12 158 
GND11 163 
GND10 164 
GND9 169 
GND8 170 
GND7 175 
GND6 178 
GND5 181 
GND4 184 
GND3 187 
GND2 190 
GND1 195 
GND0 196 
C150 
0.1UF 
X7R 
16V 
C0402 
10% 
R203 
100 
1% 
R0402 
C165 
0.1UF 
X7R 
16V 
C0402 
10% 
C140 
0.1UF 
X7R 
16V 
C0402 
10% 
C159 
0.1UF 
X7R 
16V 
C0402 
10% 
C142 
0.1UF 
X7R 
16V 
C0402 
10% 
U10 
ISL90728 
VCC 1
GND 2
SCL 3
SDA 4 RW 5
RH 6
R209 0 5% R0402 
C171 
0.1UF 
X7R 
16V 
C0402 
10% 
C151 
0.1UF 
X7R 
16V 
C0402 
10% 
C141 
10UF 6.3V 
20% 
X5R 
C0603 
C177 
10UF 6.3V 
20% 
X5R 
C0603 
C163 
0.1UF 
X7R 
16V 
C0402 
10% 
-
+
U11 
LMV321AS5X 
1
3
4
5 2
C161 
0.1UF 
X7R 
16V 
C0402 
10% 
R202 
100 
1% 
R0402 
C158 
0.1UF 
X7R 
16V 
C0402 
10% 
C181 
1UF 
X5R 
C0402 
10% 
10V 
NI 
C143 
0.1UF 
X7R 
16V 
C0402 
10% 
C194 
0.01UF 
X7R 
16V 
C0402 
10% 
R210 0 5% R0402 
C175 
10UF 6.3V 
20% 
X5R 
C0603 
C154 
0.1UF 
X7R 
16V 
C0402 
10% 
R472 0
R0402 5% 
C157 
0.1UF 
X7R 
16V 
C0402 
10% 
C176 
10UF 6.3V 
20% 
X5R 
C0603 
C162 
0.1UF 
X7R 
16V 
C0402 
10% 
C180 
0.1UF 
X7R 
16V 
C0402 
10% 
C164 
0.1UF 
X7R 
16V 
C0402 
10% 
R471 0
R0402 5% 
C160 
0.1UF 
X7R 
16V 
C0402 
10% 
R206 0 5% R0402 
R204 0 5% R0402 
C155 
0.1UF 
X7R 
16V 
C0402 
10% 
R216 2.2 
1% R0402 
R214 12.1K 
1% R0402 
J2A 
SCONN204_AS0A621HASN7H 
A15 88 
A14 90 
A13 130 
A12 95 
A11 96 
A10 117 
A9 92 
A8 97 
A7 98 
A6 100 
A5 99 
A4 104 
A3 103 
A2 106 
A1 105 
A0 107 
BA2 91 
BA1 108 
BA0 119 
CB7 82 
CB6 80 
CB5 74 
CB4 72 
CB3 83 
CB2 81 
CB1 71 
CB0 69 
CK1 112 
CK0 111 
CK1# 114 
CK0# 113 
CKE1 89 
CKE0 87 
DM8 76 
DM7 189 
DM6 172 
DM5 157 
DM4 140 
DM3 59 
DM2 44 
DM1 28 
DM0 11 
ODT1 128 
ODT0 126 
SA1 201 
SA0 197 
S3# 118 
S2# 120 
S1# 129 
S0# 127 
RAS# 122 
CAS# 125 
WE# 121 
RESET# 30 
EVENT# 198 
SDA 200 
SCL 202 
DQ63 194 
DQ62 192 
DQ61 182 
DQ60 180 
DQ59 193 
DQ58 191 
DQ57 185 
DQ56 183 
DQ55 176 
DQ54 174 
DQ53 168 
DQ52 166 
DQ51 179 
DQ50 177 
DQ49 167 
DQ48 165 
DQ47 162 
DQ46 160 
DQ45 150 
DQ44 148 
DQ43 161 
DQ42 159 
DQ41 153 
DQ40 151 
DQ39 144 
DQ38 142 
DQ37 136 
DQ36 134 
DQ35 147 
DQ34 145 
DQ33 135 
DQ32 133 
DQ31 68 
DQ30 66 
DQ29 56 
DQ28 54 
DQ27 65 
DQ26 63 
DQ25 57 
DQ24 55 
DQ23 50 
DQ22 48 
DQ21 42 
DQ20 40 
DQ19 51 
DQ18 49 
DQ17 39 
DQ16 37 
DQ15 36 
DQ14 34 
DQ13 24 
DQ12 22 
DQ11 33 
DQ10 31 
DQ9 21 
DQ8 19 
DQ7 18 
DQ6 16 
DQ5 6
DQ4 4
DQ3 15 
DQ2 13 
DQ1 7
DQ0 5
DQS8 77 
DQS7 188 
DQS6 173 
DQS5 156 
DQS4 141 
DQS3 62 
DQS2 45 
DQS1 27 
DQS0 12 
DQS8# 75 
DQS7# 186 
DQS6# 171 
DQS5# 154 
DQS4# 139 
DQS3# 60 
DQS2# 43 
DQS1# 25 
DQS0# 10 
G1 G1 
G2 G2 
C148 
0.1UF 
X7R 
16V 
C0402 
10% 
C144 
0.1UF 
X7R 
16V 
C0402 
10% 
C178 
10UF 6.3V 
20% 
X5R 
C0603 
C146 
0.1UF 
X7R 
16V 
C0402 
10% 
C153 
0.1UF 
X7R 
16V 
C0402 
10% 
R213 
12.1K 
1% 
R0402 
C174 
10UF 6.3V 
20% 
X5R 
C0603 
R212 0 5% R0402 
C166 
0.1UF 
X7R 
16V 
C0402 
10% 
R218 
100 
1% 
R0402 
C156 
0.1UF 
X7R 
16V 
C0402 
10% 
C168 
0.1UF 
X7R 
16V 
C0402 
10% 
R215 
100 
1% 
R0402 
NI 



5
5
4
4
3
3
2
2
1
1
D D
C C
B B
A A
Title 
Size Document Number Rev
Date: Sheet 
of 
Blank 1A
Chassis Manager Assembly V1 
Cloud Server Infrastructure Engineering
C
28 85Monday, January 27, 2014 
Title 
Size Document Number Rev
Date: Sheet 
of 
Blank 1A
Chassis Manager Assembly V1 
Cloud Server Infrastructure Engineering
C
28 85Monday, January 27, 2014 
Title 
Size Document Number Rev
Date: Sheet 
of 
Blank 1A
Chassis Manager Assembly V1 
Cloud Server Infrastructure Engineering
C
28 85Monday, January 27, 2014 



5
5
4
4
3
3
2
2
1
1
D D
C C
B B
A A
Title 
Size Document Number Rev
Date: Sheet 
of 
BLANK 1A
Chassis Manager Assembly V1 
Cloud Server Infrastructure Engineering
C
29 85Monday, January 27, 2014 
Title 
Size Document Number Rev
Date: Sheet 
of 
BLANK 1A
Chassis Manager Assembly V1 
Cloud Server Infrastructure Engineering
C
29 85Monday, January 27, 2014 
Title 
Size Document Number Rev
Date: Sheet 
of 
BLANK 1A
Chassis Manager Assembly V1 
Cloud Server Infrastructure Engineering
C
29 85Monday, January 27, 2014 



5
5
4
4
3
3
2
2
1
1
D D
C C
B B
A A
One 0.1u CAP per pin 
FOR VDDR 
One 0.1u CAP per 
pin 
FOR VDDAUX 
One 0.1u CAP per pin 
FOR VAUX 
Pin has an internal pull-up 
One 0.1u CAP per pin 
FOR VDDC 
One 0.1u CAP per pin 
FOR VDDA 
FOR VDDA 
P2E_CPU_PCIE_SW_NODE1_RX_C_DN 
P2E_CPU_PCIE_SW_NODE1_RX_C_DP 
P2E_CPU_PCIE_SW_NODE1_RX_C_DN 
P2E_CPU_PCIE_SW_NODE1_RX_C_DP 
P2E_CPU_BMC_NODE1_TX_C_DN 
P2E_CPU_BMC_NODE1_TX_C_DP 
P2E_CPU_USB_NODE1_TX_C_DN 
P2E_CPU_USB_NODE1_TX_C_DP P2E_CPU_BMC_NODE1_TX_C_DN 
P2E_CPU_BMC_NODE1_TX_C_DP 
PCIE_SW_PRSNT1 
PCIE_SW_PRSNT2 
P2E_CPU_USB_NODE1_TX_C_DN 
P2E_CPU_USB_NODE1_TX_C_DP 
PCIE_SW_RST_N 
PCIE_SW_P0_ERR 
PCIE_SW_RST_N 
PCIE_SW_WAKE_N 
PCIE_SW_WAKE_N 
PCIE_SW_PRSNT2 
PCIE_SW_PRSNT1 
PCIE_SW_SLOTCLK 
PCIE_SW_SLOTCLK 
PCIE_SW_TEST6 
PCIE_SW_TEST5 
PCIE_SW_TEST4 
PCIE_SW_TEST3 
PCIE_SW_WP_N 
PCIE_SW_EEPROM_CLK 
PCIE_SW_EEPROM_DAT 
PCIE_SW_EEPROM_CLK 
PCIE_SW_EEPROM_DAT 
PCIE_SW_EEPROM_CLK 
PCIE_SW_EEPROM_DAT 
PCIE_SW_SCAN_EN 
PCIE_SW_SCAN_EN 
PCIE_SW_I2C_SCL 
PCIE_SW_I2C_SDA 
PCIE_SW_I2C_SDA 
PCIE_SW_I2C_SCL 
PCIE_SW_PWR_SAV 
PCIE_SW_PWR_SAV 
PCIE_SW_P0_CTCDIS 
PCIE_SW_P1_CTCDIS 
PCIE_SW_P2_CTCDIS 
PCIE_SW_P2_CTCDIS 
PCIE_SW_P0_CTCDIS 
PCIE_SW_P1_CTCDIS 
PCIE_SW_TEST7 
PCIE_SW_TEST1 
PCIE_SW_TEST2 
PCIE_SW_TEST5 
PCIE_SW_TEST4 
PCIE_SW_TEST1 
PCIE_SW_TEST6 
PCIE_SW_TEST3 
PCIE_SW_TEST7 
PCIE_SW_TEST2 
PCIE_SW_TMS 
PCIE_SW_TRST 
PCIE_SW_TMS 
PCIE_SW_TRST 
PCIE_SW_WP_N 
PCIE_SW_P0_ERR_R 
PCIE_SW_P0_ERR_R 
PCIE_SW_GPIO5 
PCIE_SW_GPIO6 
PCIE_SW_GPIO7 
PCIE_SW_GPIO5 
PCIE_SW_GPIO6 
PCIE_SW_GPIO7 
PCIE_SW_I2C_SCL 
PCIE_SW_I2C_SDA 
CLK_100M_PCIE_SW_NODE1_C_DP 
CLK_100M_PCIE_SW_NODE1_C_DN 
CLK_100M_PCIE_SW_NODE1_C_DN 
CLK_100M_PCIE_SW_NODE1_C_DP 
PE_SW_USB_PERST_L 
PE_SW_BMC_PERST_L 
P2E_CPU_PCIE_SW_NODE1_RX_DP 
P2E_CPU_PCIE_SW_NODE1_RX_DN 
P2E_CPU_PCIE_SW_NODE1_TX_DP (15) 
P2E_CPU_PCIE_SW_NODE1_TX_DN (15) 
P2E_CPU_BMC_NODE1_TX_DP 
P2E_CPU_BMC_NODE1_TX_DN 
P2E_CPU_USB_NODE1_TX_DP 
P2E_CPU_USB_NODE1_TX_DN 
P2E_CPU_BMC_NODE1_RX_DP (32) 
P2E_CPU_BMC_NODE1_RX_DN (32) 
FM_CPLD_PCIE_SW_PERST_L (67) 
IRQ_LVC3_CPU_NODE1_WAKE_L (32,45,47,49,50,67) 
P2E_CPU_USB_NODE1_RX_DP (47) 
P2E_CPU_USB_NODE1_RX_DN (47) 
PE_SW_BMC_PERST_L 
PE_SW_USB_PERST_L 
SMB_CPU_NODE1_BMC_CLK (18) 
SMB_CPU_NODE1_BMC_DAT (18,66) 
PCIE_SW_P0_ERR 
CLK_100M_PCIE_SW_NODE1_DP (13) 
CLK_100M_PCIE_SW_NODE1_DN (13) 
P3V3_NODE1 
P3V3_NODE1 
P3V3_NODE1 
P1V0_NODE1 
P3V3_NODE1 
P3V3_NODE1 
P3V3_NODE1 
P3V3_NODE1
P1V0_NODE1 
P1V0_NODE1 
P3V3_NODE1 
P1V0_PCI_SW_A 
P1V0_NODE1 P1V0_PCI_SW_A 
P1V0_NODE1 
P3V3_NODE1 
P1V0_NODE1 
P1V0_PCI_SW_A 
P1V538_BMC_NODE1 
P1V538_BMC_NODE1 
Title 
Size Document Number Rev
Date: Sheet 
of 
PCIe Switch 1A
Chassis Manager Assembly V1 
Cloud Server Infrastructure Engineering
C
30 85Monday, January 27, 2014 
Title 
Size Document Number Rev
Date: Sheet 
of 
PCIe Switch 1A
Chassis Manager Assembly V1 
Cloud Server Infrastructure Engineering
C
30 85Monday, January 27, 2014 
Title 
Size Document Number Rev
Date: Sheet 
of 
PCIe Switch 1A
Chassis Manager Assembly V1 
Cloud Server Infrastructure Engineering
C
30 85Monday, January 27, 2014 
C882 
0.1UF 
X7R 
16V 
10% 
C0402 
NI 
R288 5.1K 
R0402 1% 
NI 
C868 
0.1UF 
X7R 
16V 
10% 
C0402 
NI 
C873 
0.1UF 
X7R 
16V 
10% 
C0402 
NI 
C863 
0.1UF 
X7R 
16V 
10% 
C0402 
NI 
U125B 
PI7C9X20303SLFDE 
NI 
NC1 9
PRSNT2 7
PRSNT1 128 
TEST5 10 
TEST4 11 
TEST3 12 
SLOTCLK 127 
JTG_TCK 59 
JTG_TMS 63 
JTG_TDO 58 
JTG_TDI 64 
JTG_TRST_L 65 
NC2 54 
PORTERR2 51 
PORTERR1 47 
PORTERR0 45 
SCAN_EN 56 TEST1 31 TEST2 66 
TEST6 126 
P1_CTCDIS 32 
P2_CTCDIS 33 
SCL_I 13 
SDA_I 16 
PWR_SAV 17 
P0_CTCDIS 18 
EECLK 40 
EEPD 41 
TEST7 38 
GPIO0 21 GPIO1 22 GPIO2 23 GPIO3 24 GPIO4 25 GPIO5 26 GPIO6 27 GPIO7 28 
R289 5.1K 
R0402 1% 
NI 
R277 5.1K 
R0402 1% 
NI 
R284 5.1K 
R0402 1% 
NI 
C892 
0.1UF 
X7R 
16V 
10% 
C0402 
NI 
C192 0.1UF 
X7R C0402 
10% 16V 
NI 
R305 5.1K 
R0402 1% 
NI 
C874 
0.1UF 
X7R 
16V 
10% 
C0402 
NI 
R278 5.1K 
R0402 1% 
NI 
C330 
0.1UF 
X7R 
16V 
10% 
C0402 
NI 
C869 
0.1UF 
X7R 
16V 
10% 
C0402 
NI 
R234 0
5% R0402 
NI 
C199 
10UF 10V 
20% 
X5R 
C0603 
NI 
C896 
0.1UF 
X7R 
16V 
10% 
C0402 
NI 
R283 5.1K 
R0402 1% 
NI 
C888 
0.1UF 
X7R 
16V 
10% 
C0402 
NI 
C186 0.1UF 
X7R C0402 
10% 16V 
NI 
C889 
0.1UF 
X7R 
16V 
10% 
C0402 
NI 
C191 0.1UF 
X7R 16V 
C0402 10% 
NI 
U125C 
PI7C9X20303SLFDE 
NI 
PERST_L 43 
REFCLK_N 93 REFCLK_P 91 
WAKE_L 6
DWNRST1_L 96 DWNRST2_L 97 NC3 98 
RXP00 70 
RXN00 69 TXP00 73 
TXN00 74 
NC6 120 
NC7 121 NC5 117 
NC4 116 
RXP02 104 
RXN02 103 TXP02 107 
TXN02 108 
RXP01 87 
RXN01 88 TXP01 84 
TXN01 83 
R279 5.1K 
R0402 1% 
NI 
R285 5.1K 
R0402 1% 
NI 
C865 
0.1UF 
X7R 
16V 
10% 
C0402 
NI 
C875 
0.1UF 
X7R 
16V 
10% 
C0402 
NI 
C893 
0.1UF 
X7R 
16V 
10% 
C0402 
NI 
C188 0.1UF 
X7R C0402 
10% 16V 
NI 
R303 5.1K 
R0402 1% 
NI 
C185 0.1UF 
X7R C0402 
10% 16V 
NI 
C331 
0.1UF 
X7R 
16V 
10% 
C0402 
NI 
C870 
0.1UF 
X7R 
16V 
10% 
C0402 
NI 
C881 
0.1UF 
X7R 
16V 
10% 
C0402 
NI 
C200 
10UF 10V 
20% 
X5R 
C0603 
NI 
R286 5.1K 
R0402 1% 
NI 
C890 
0.1UF 
X7R 
16V 
10% 
C0402 
NI 
R275 5.1K 
R0402 1% 
NI 
C876 
0.1UF 
X7R 
16V 
10% 
C0402 
NI 
R308 5.1K 
R0402 1% 
NI 
C861 
0.1UF 
X7R 
16V 
10% 
C0402 
NI 
R1226 100 
R0402 1% 
NI 
R295 5.1K 
R0402 1% 
NI 
C897 
0.1UF 
X7R 
16V 
10% 
C0402 
NI 
R280 5.1K 
R0402 1% 
NI 
R231 0
5% R0402 
NI 
C894 
0.1UF 
X7R 
16V 
10% 
C0402 
NI 
C187 0.1UF 
X7R C0402 
10% 16V 
NI 
C878 
0.1UF 
X7R 
16V 
10% 
C0402 
NI 
C891 
0.1UF 
X7R 
16V 
10% 
C0402 
NI 
R232 0
5% R0402 
NI 
C864 
0.1UF 
X7R 
16V 
10% 
C0402 
NI 
R296 5.1K 
R0402 1% 
NI 
R301 5.1K 
R0402 1% 
NI 
C877 
0.1UF 
X7R 
16V 
10% 
C0402 
NI 
R281 5.1K 
R0402 1% 
NI 
R309 5.1K 
R0402 1% 
NI 
C866 
0.1UF 
X7R 
16V 
10% 
C0402 
NI 
R306 5.1K 
R0402 1% 
NI 
C930 
0.1UF 
X7R 
16V 
10% 
C0402 
NI 
R1228 100 
R0402 1% 
NI 
R310 5.1K 
R0402 1% 
NI 
C190 0.1UF 
X7R C0402 
10% 16V 
NI 
R263 0 NI 
R307 5.1K 
R0402 1% 
NI 
C862 
0.1UF 
X7R 
16V 
10% 
C0402 
NI 
U125A 
PI7C9X20303SLFDE 
NI 
VSS1 2
VSS2 3
VSS3 14 
VSS4 19 
VSS5 30 
VSS6 34 
VSS7 36 
VSS8 44 
VSS9 50 
VSS10 53 
VSS11 57 
VSS12 60 
VSS13 62 
VSS14 67 
VSS15 68 
VSS16 71 
VSS17 77 
VSS18 81 
VSS19 86 
VSS20 89 
VSS21 90 
VSS22 94 
VSS23 95 
VSS24 100 
VSS25 102 
VSS26 105 
VSS27 111 
VSS28 114 
VSS29 119 
VSS30 122 
VSS31 125 
VDDC1 1
VDDC2 15 
VDDC3 29 
VDDC4 37 
VDDC5 42 
VDDC6 46 
VDDC7 49 
VDDC8 52 
VDDC9 61 
VDDC10 101 
VDDC11 123 
VDDR1 8
VDDR2 20 
VDDR3 35 
VDDR4 39 
VDDR5 48 
VDDR6 55 
VDDR7 99 
VDDR8 124 
VDDAUX2 76 
VDDAUX3 110 
VDDAUX1 4
VAUX 5
VDDA1 78 
VDDA2 79 
VDDA3 80 
VDDA4 92 
VDDA5 112 
VDDA6 113 
VTT1 75 
VTT2 82 
VTT3 109 
VTT4 115 
VDDC12 72 
VDDC13 85 
VDDC14 106 
VDDC15 118 
C879 
0.1UF 
X7R 
16V 
10% 
C0402 
NI 
R1229 100 
R0402 1% 
NI 
R233 0
5% R0402 
NI 
C931 
0.1UF 
X7R 
16V 
10% 
C0402 
NI 
L53 
220/2000MA 
NI 
21
R1227 100 
R0402 1% 
NI 
C189 0.1UF 
X7R C0402 
10% 16V 
NI 
C193 0.1UF 
X7R C0402 
10% 16V 
NI 
R287 5.1K 
R0402 1% 
NI 
U13 
M24C04-WMN6TP 
NI 
VCC 8
WP 7
SCL 6
SDA 5 GND 4A2 3A1 2A0 1
C867 
0.1UF 
X7R 
16V 
10% 
C0402 
NI 
C871 
0.1UF 
X7R 
16V 
10% 
C0402 
NI 
R276 5.1K 
R0402 1% 
NI 
C872 
0.1UF 
X7R 
16V 
10% 
C0402 
NI 
C895 
0.1UF 
X7R 
16V 
10% 
C0402 
NI 
R297 5.1K 
R0402 1% 
NI 
C932 
0.1UF 
X7R 
16V 
10% 
C0402 
NI 
C880 
0.1UF 
X7R 
16V 
10% 
C0402 
NI 
R299 5.1K 
R0402 1% 
NI 



5
5
4
4
3
3
2
2
1
1
D D
C C
B B
A A
Title 
Size Document Number Rev
Date: Sheet 
of 
Blank 1A
Chassis Manager Assembly V1 
Cloud Server Infrastructure Engineering
C
31 85Monday, January 27, 2014 
Title 
Size Document Number Rev
Date: Sheet 
of 
Blank 1A
Chassis Manager Assembly V1 
Cloud Server Infrastructure Engineering
C
31 85Monday, January 27, 2014 
Title 
Size Document Number Rev
Date: Sheet 
of 
Blank 1A
Chassis Manager Assembly V1 
Cloud Server Infrastructure Engineering
C
31 85Monday, January 27, 2014 



5
5
4
4
3
3
2
2
1
1
D D
C C
B B
A A
Place Near pin 
VGA OLNY 
RST_BMC_NODE1_PERST_L 
PD_BMC_NODE1_PEREXT 
P2E_CPU_BMC_NODE1_RX_C_DP 
P2E_CPU_BMC_NODE1_RX_C_DN IRQ_LVC3_CPU_NODE1_WAKE_R_L 
BMC_NODE1_DDR_IOZ 
LPC_CLK_AST 
LPC_CLK_AST 
BMC_NODE1_DDR_IOZ 
RST_BMC_NODE1_PERST_L 
PU_I2C_BMC_SDA 
PU_I2C_BMC_SCL 
PU_I2C_BMC_SCL 
PU_I2C_BMC_SDA 
PD_BMC_LPC 
PD_BMC_LPC 
PD_BMC_LPC 
BMC_NODE1_DDR_DQS1_DN (33) 
BMC_NODE1_DDR_DM0 (33) 
BMC_NODE1_DDR_CLK_DP (33) 
BMC_NODE1_DDR_CLK_DN (33) 
BMC_NODE1_DDR_CKE (33) 
BMC_NODE1_DDR_ODT 
BMC_NODE1_DDR_CAS_L (33) 
BMC_NODE1_DDR_WE_L (33) 
BMC_NODE1_DDR_CS_L (33) 
BMC_NODE1_DDR_RAS_L (33) 
BMC_NODE1_DDR_BA0 
BMC_NODE1_DDR_BA1 
BMC_NODE1_DDR_BA2 
BMC_NODE1_DDR_DQS0_DN (33) 
BMC_NODE1_DDR_DQS1_DP (33) 
BMC_NODE1_DDR_DQS0_DP (33) 
CLK_100M_BMC_NODE1_DP (13) 
CLK_100M_BMC_NODE1_DN (13) 
P2E_CPU_BMC_NODE1_TX_DP 
P2E_CPU_BMC_NODE1_TX_DN 
P2E_CPU_BMC_NODE1_RX_DP (30) 
P2E_CPU_BMC_NODE1_RX_DN (30) 
BMC_NODE1_DDR_D2 (33) 
BMC_NODE1_DDR_D0 (33) 
BMC_NODE1_DDR_D5 (33) 
BMC_NODE1_DDR_D3 (33) 
BMC_NODE1_DDR_D4 (33) 
BMC_NODE1_DDR_D6 (33) 
BMC_NODE1_DDR_D7 (33) 
BMC_NODE1_DDR_D1 (33) 
BMC_NODE1_DDR_D11 (33) 
BMC_NODE1_DDR_D9 (33) 
BMC_NODE1_DDR_D10 (33) 
BMC_NODE1_DDR_D14 (33) 
BMC_NODE1_DDR_D12 (33) 
BMC_NODE1_DDR_D13 (33) 
BMC_NODE1_DDR_D8 (33) 
BMC_NODE1_DDR_D15 (33) 
BMC_NODE1_DDR_MA0 (33) 
BMC_NODE1_DDR_MA1 (33) 
BMC_NODE1_DDR_MA2 (33) 
BMC_NODE1_DDR_MA3 (33) 
BMC_NODE1_DDR_MA4 (33) 
BMC_NODE1_DDR_MA5 (33) 
BMC_NODE1_DDR_MA6 (33) 
BMC_NODE1_DDR_MA7 (33) 
BMC_NODE1_DDR_MA8 (33) 
BMC_NODE1_DDR_MA9 (33) 
BMC_NODE1_DDR_MA10 (33) 
BMC_NODE1_DDR_MA11 (33) 
BMC_NODE1_DDR_MA12 (33) 
BMC_NODE1_DDR_MA13 (33) 
BMC_NODE1_DDR_MA14 (33) 
FM_CPLD_NODE1_BMC_PERST_L (67) 
BMC_NODE1_DDR_DM1 (33) 
IRQ_LVC3_CPU_NODE1_WAKE_L (19,30,67) 
PE_SW_BMC_PERST_L 
P0V75_BMC_VTTREF_NODE1 
P3V3_NODE1 
Title 
Size Document Number Rev
Date: Sheet 
of 
Node1 AST1300 DDRIII & I2C 1A
Chassis Manager Assembly V1 
Cloud Server Infrastructure Engineering
C
32 85Monday, January 27, 2014 
Title 
Size Document Number Rev
Date: Sheet 
of 
Node1 AST1300 DDRIII & I2C 1A
Chassis Manager Assembly V1 
Cloud Server Infrastructure Engineering
C
32 85Monday, January 27, 2014 
Title 
Size Document Number Rev
Date: Sheet 
of 
Node1 AST1300 DDRIII & I2C 1A
Chassis Manager Assembly V1 
Cloud Server Infrastructure Engineering
C
32 85Monday, January 27, 2014 
R254 0 NI 
C205 
0.1UF 
C0402 
10% 
16V 
X7R 
NI 
PCI-Express 
DDR2/DDR3 
LPC 
I2C 
SD/SDIO PS2 
U14A 
AST1300A1-GP 
NI 
PERST# K19 
PEWAKE# J22 
PERXP F21 
PERXN F22 
PEREFCLKP G22 
PEREFCLKN G21 PEREXT D20 
PETXP E22 
PETXN E21 
MDQ0 W12 
MDQ1 V12 
MDQ2 AB11 
MDQ3 AA11 
MDQ4 Y11 
MDQ5 W11 
MDQ6 V11 
MDQ7 Y10 
MDQ8 V10 
MDQ9 AB9 
MDQ10 AA9 
MDQ11 Y9 
MDQ12 W9 
MDQ13 V9 
MDQ14 Y8 
MDQ15 W8 
MDQS0 AB10 
MDQS1 AA8 
MDQS0# AA10 
MDQS1# AB8 
MCK AB12 
MCK# AA12 
MCKE Y12 
MODT V14 
MCS# AA13 
MRAS# W13 
MCAS# AB13 
MWE# Y13 
MDM0 W10 
MDM1 V8 
MBA0 W14 
MBA1 AA14 
MBA2 Y14 
MA0 AB14 
MA1 W15 
MA2 V15 
MA3 Y16 
MA4 AB15 
MA5 W16 
MA6 AA15 
MA7 AB18 
MA8 AB16 
MA9 AA17 
MA10 Y15 
MA11 AA16 
MA12 W17 
MA13 Y17 
MA14 AB17 
MIOZ V16 
MVREF V13 
LCLK B20 
LFRAME# A21 
LSIRQ# E17 
LAD0 B21 
LAD1 A22 
LAD2 F19 
LAD3 C19 
SCL1 K21 
SDA1 K22 
SCL2 J19 
SDA2 J18 
GPIOQ0_SCL3 D3 
GPIOQ1_SDA3 C2 
GPIOQ2_SCL4 B1 
GPIOQ3_SDA4 F5 
GPIOK0_SCL5 E3 
GPIOK1_SDA5 D2 
GPIOK2_SCL6 C1 
GPIOK3_SDA6 F4 
GPIOK4_SCL7_SALT3 E2 
GPIOK5_SDA7_SALT4 D1 
GPIOK6_SCL8_SALT1 G5 
GPIOK7_SDA8_SALT2 F3 
GPIOQ4_KBCLK H4 
GPIOQ5_KBDAT H3 
GPIOQ6_MSCLK H2 
GPIOQ7_MSDAT H1 
GPIOC0_SD1CLK C4 
GPIOC1_SD1CMD B3 
GPIOC2_SD1DAT0 A2 
GPIOC3_SD1DAT1 E5 
GPIOC4_SD1DAT2 D4 
GPIOC5_SD1DAT3 C3 
GPIOC6_SD1CD# B2 
GPIOC7_SD1WP# A1 
GPIOA4_TIMER5_SCL9 C5 
GPIOA5_TIMER6_SDA9 B4 
GPIOB0_SALT1 J21 
GPIOB1_SALT2 J20 
GPIOB2_SALT3 H18 
GPIOB3_SALT4 F18 
GPIOD0_SD2CLK A18 
GPIOD1_SD2CMD D16 
GPIOD2_SD2DAT0 B17 
GPIOD3_SD2DAT1 A17 
GPIOD4_SD2DAT2 C16 
GPIOD5_SD2DAT3 B16 
GPIOD6_SD2CD# A16 
GPIOD7_SD2WP# E15 
R253 100K 
5% R0402 
NI 
R1230 1K 
1% R0402 
NI 
R256 10K 
R0402 1% 
NI 
R345 4.7K 
5% R0402 
NI 
R258 100K 
5% R0402 
NI 
R346 4.7K NI 
5% R0402 
C204 
0.01UF 16V 
X7R 
C0402 
10% 
NI 
R272 0 NI 
C202 0.1UF 
C0402 
X7R 16V 
10% 
NI 
C203 0.1UF 
C0402 
X7R 16V 
10% 
NI R255 0
NI 
R257 274 
R0402 1% 
NI 



5
5
4
4
3
3
2
2
1
1
D D
C C
B B
A A
CAD Note: 
TRACE WIDTH >=15MIL 
CAD Note: 
Place near pin H1,M8 
Place near DRAM Power pin 
TP_BMC_NODE1_DDR3_CE1_NC1 
TP_BMC_NODE1_DDR3_ODT_1NC 
TP_BMC_NODE1_DDR3_ZQ1 
TP_BMC_NODE1_DDR3_CS1_L 
BMC_NODE1_DDR3_ZQ 
TP_BMC_NODE1_DDR3_MA15 
BMC_NODE1_DDR_RST_L FM_BMC_NODE1_RESET_L 
BMC_NODE1_DDR_RST_L 
BMC_NODE1_DDR_MA0 (32) 
BMC_NODE1_DDR_ODT 
BMC_NODE1_DDR_D8 (32) 
BMC_NODE1_DDR_CKE (32) 
BMC_NODE1_DDR_CLK_DP (32) 
BMC_NODE1_DDR_CLK_DN (32) 
BMC_NODE1_DDR_BA0 
BMC_NODE1_DDR_CS_L (32) 
BMC_NODE1_DDR_WE_L (32) 
BMC_NODE1_DDR_CAS_L (32) 
BMC_NODE1_DDR_RAS_L (32) 
BMC_NODE1_DDR_D14 (32) 
BMC_NODE1_DDR_MA1 (32) 
BMC_NODE1_DDR_DQS1_DN (32) 
BMC_NODE1_DDR_BA1 
BMC_NODE1_DDR_MA2 (32) 
BMC_NODE1_DDR_BA2 
BMC_NODE1_DDR_MA3 (32) 
BMC_NODE1_DDR_MA4 (32) 
BMC_NODE1_DDR_DM0 (32) 
BMC_NODE1_DDR_DM1 (32) 
BMC_NODE1_DDR_MA5 (32) 
BMC_NODE1_DDR_MA6 (32) 
BMC_NODE1_DDR_MA7 (32) 
BMC_NODE1_DDR_MA8 (32) 
BMC_NODE1_DDR_MA9 (32) 
BMC_NODE1_DDR_MA10 (32) 
BMC_NODE1_DDR_MA11 (32) 
BMC_NODE1_DDR_MA12 (32) 
BMC_NODE1_DDR_MA13 (32) 
BMC_NODE1_DDR_MA14 (32) 
BMC_NODE1_DDR_D7 (32) 
BMC_NODE1_DDR_D10 (32) 
BMC_NODE1_DDR_D13 (32) 
BMC_NODE1_DDR_D1 (32) 
BMC_NODE1_DDR_D4 (32) 
BMC_NODE1_DDR_D9 (32) 
BMC_NODE1_DDR_DQS0_DN (32) 
BMC_NODE1_DDR_D12 (32) 
BMC_NODE1_DDR_DQS0_DP (32) 
BMC_NODE1_DDR_D11 (32) 
BMC_NODE1_DDR_D5 (32) 
BMC_NODE1_DDR_D2 (32) 
BMC_NODE1_DDR_D0 (32) 
BMC_NODE1_DDR_D3 (32) 
BMC_NODE1_DDR_D15 (32) 
BMC_NODE1_DDR_DQS1_DP (32) 
BMC_NODE1_DDR_D6 (32) 
FM_BMC_NODE1_RESET_L (35) 
P0V75_BMC_VTTREF_NODE1 
P0V75_BMC_VTTREF_NODE1 
P1V538_BMC_NODE1 
P1V538_BMC_NODE1 
P1V538_BMC_NODE1 
P3V3_NODE1 
P1V538_BMC_NODE1 
Title 
Size Document Number Rev
Date: Sheet 
of 
Node1 AST1300 DDRIII Memory 1A
Chassis Manager Assembly V1 
Cloud Server Infrastructure Engineering
C
33 85Monday, January 27, 2014 
Title 
Size Document Number Rev
Date: Sheet 
of 
Node1 AST1300 DDRIII Memory 1A
Chassis Manager Assembly V1 
Cloud Server Infrastructure Engineering
C
33 85Monday, January 27, 2014 
Title 
Size Document Number Rev
Date: Sheet 
of 
Node1 AST1300 DDRIII Memory 1A
Chassis Manager Assembly V1 
Cloud Server Infrastructure Engineering
C
33 85Monday, January 27, 2014 
C229 
10UF 
X5R 
6.3V 
20% 
C0603 
NI 
C226 
0.01UF 16V 
X7R 
C0402 
10% 
NI 
C230 
0.1UF 
X7R 
16V 
10% 
C0402 
NI 
U16 
SN74LVC1G07DCKR 
NI 
VCC 5
A2
GND 3
Y 4
NC 1
C228 
0.01UF 16V 
X7R 
C0402 
10% 
NI 
R261 
1K 
1% 
1/16W 
R0402 
NI 
C234 
0.1UF 
X7R 
16V 
10% 
C0402 
NI 
C235 
0.1UF 
X7R 
16V 
10% 
C0402 
NI 
R259 
4.7K 
5% 
R0402 
NI 
C231 
0.1UF 
X7R 
16V 
10% 
C0402 
NI 
C225 0.1UF 
C0402 
X7R 16V 
10% 
NI 
C223 
0.1UF 
C0402 
10% 
16V 
X7R 
NI 
R262 
1K 
1% 
1/16W 
R0402 
NI 
C224 
0.01UF 16V 
X7R 
C0402 
10% 
NI 
C232 
0.1UF 
X7R 
16V 
10% 
C0402 
NI 
C227 
1UF 6.3V 
10% 
X7R 
C0402 
NI 
U15 
K4B1G1646E-HCF8 
NI 
VDD8 R9 
VDD7 R1 
VDD6 N9 
VDD5 N1 
VDD4 K8 
VDD3 K2 
VDD2 G7 
VDD1 D9 
VDD0 B2 
VDDQ8 H9 
VDDQ7 H2 
VDDQ6 F1 
VDDQ5 E9 
VDDQ4 D2 
VDDQ3 C9 
VDDQ2 C1 
VDDQ1 A8 
VDDQ0 A1 
A15_BA3 M7 
A14 T7 
A13 T3 
A12 N7 
A11 R7 
A10_AP L7 
A09 R3 
A08 T8 
A07 R2 
A06 R8 
A05 P2 
A04 P8 
A03 N2 
A02 P3 
A01 P7 
A0 N3 
WE_N L3 
RESET_N T2 
RAS_N J3 
ODT_ODTO K1 
DMU D3 
DML E7 
CS_N_CSO_N L2 
CKE_CKEO K9 
CK_N K7 
CK J7 
CAS_N K3 
BA2 M3 
BA1 N8 
BA0 M2 
ZQ_ZQO L8 
VSS9 P9 
VSS8 P1 
VSS7 M9 
VSS6 M1 
VSS5 J8 
VSS4 J2 
VSS3 G8 
VSS2 E1 
VSS1 B3 
VSS0 A9 
VSS10 T1 VSS11 T9 VSSQ0 B1 
VSSQ8 G9 
VSSQ7 G1 
VSSQ6 F9 
VSSQ5 E8 
VSSQ4 E2 
VSSQ3 D8 
VSSQ2 D1 
VSSQ1 B9 
VREFCA M8 VREFDQ H1 DQL0 E3 
DQL7 H7 
DQL6 G2 
DQL5 H8 
DQL4 H3 
DQL3 F8 
DQL2 F2 
DQL1 F7 
DQSL F3 DQSL_N G3 DQSU C7 DQSU_N B7 DQU0 D7 
DQU7 A3 
DQU6 B8 
DQU5 A2 
DQU4 A7 
DQU3 C2 
DQU2 C8 
DQU1 C3 
ODT_1NC J1 CE1_NC1 J9 CS1_N_NC L1 ZQ1_NC L9 
C233 
0.1UF 
X7R 
16V 
10% 
C0402 
NI 
C236 
0.1UF 
X7R 
16V 
10% 
C0402 
NI 
R260 
240 
1% 
R0402 
NI 



5
5
4
4
3
3
2
2
1
1
D D
C C
B B
A A
VGA OLNY 
BMC_ROMA0 
BMC_ROMA1 
BMC_ROMA4 
BMC_ROMA5 
BMC_ROMA6 
BMC_ROMA7 
BMC_ROMA2 
BMC_ROMA3 
BMC_ROMA8 
BMC_ROMA9 
BMC_ROMA12 
BMC_ROMA13 
BMC_ROMA14 
BMC_ROMA15 
BMC_ROMA10 
BMC_ROMA11 
BMC_ROMA17 
BMC_ROMA18 
BMC_ROMA19 
BMC_ROMA20 
BMC_ROMA16 
BMC_ROMA21 
BMC_ROMA23 
BMC_ROMA22 
BMC_ROMD0 
BMC_ROMD1 
BMC_ROMD2 
BMC_ROMD3 
BMC_ROMD4 
Title 
Size Document Number Rev
Date: Sheet 
of 
Node1 AST1300 SPI UART MAC 1A
Chassis Manager Assembly V1 
Cloud Server Infrastructure Engineering
C
34 85Monday, January 27, 2014 
Title 
Size Document Number Rev
Date: Sheet 
of 
Node1 AST1300 SPI UART MAC 1A
Chassis Manager Assembly V1 
Cloud Server Infrastructure Engineering
C
34 85Monday, January 27, 2014 
Title 
Size Document Number Rev
Date: Sheet 
of 
Node1 AST1300 SPI UART MAC 1A
Chassis Manager Assembly V1 
Cloud Server Infrastructure Engineering
C
34 85Monday, January 27, 2014 
BMC NOR/NAND/SPI System 
 UART 
BMC UART 
MAC1 
MAC3 
MAC2 
MAC4 
System 
  SPI 
U14B 
AST1300A1-GP 
NI 
ROMA0 R20 
ROMA1 R21 
ROMA2 R22 
ROMA3 P18 
ROMA4 P19 
ROMA5 P20 
ROMA6 P21 
ROMA7 P22 
ROMA8 M19 
ROMA9 M20 
ROMA10 M21 
ROMA11 M22 
ROMA12 L18 
ROMA13 L19 
ROMA14 L20 
ROMA15 L21 
ROMA16 T18 
ROMA17 N18 
ROMA18 N19 
ROMA19 M18 
ROMA20 N22 
ROMA21 N20 
ROMA22_GPIOS6 L22 
ROMA23_GPIOS7 K18 
GPIOR4_ROMA24 V21 
GPIOR5_ROMA25 W22 
ROMCS0# R19 
GPIOR0_ROMCS1# V20 
GPIOR1_ROMCS2# W21 
GPIOR2_ROMCS3# Y22 
GPIOR3_ROMCS4# U19 
ROMOE#_GPIOS4 R18 
ROMWE#_GPIOS5 N21 
ROMD0 T22 
ROMD1 T21 
ROMD2 T20 
ROMD3 U22 
ROMD4_GPIOS0 U21 
ROMD5_GPIOS1 T19 
ROMD6_GPIOS2 V22 
ROMD7_GPIOS3 U20 
GPIOH0_ROMD8_RMII3CRSDV A8 
GPIOH1_ROMD9_RMII3RXER C7 
GPIOH2_ROMD10_RMII3RXD0 B7 
GPIOH3_ROMD11_RMII3RXD1 A7 
GPIOH4_ROMD12_RMII4CRSDV D7 
GPIOH5_ROMD13_RMII4RXER B6 
GPIOH6_ROMD14_RMII4RXD0 A6 
GPIOH7_ROMD15_RMII4RXD1 E7 
GPIOL0_NCTS1 U1 
GPIOL1_NDCD1_VPDE T5 
GPIOL2_NDSR1_VPODD U3 
GPIOL3_NRI1_VPHS V1 
GPIOL4_NDTR1_VPVS U4 
GPIOL5_NRTS1_VPCLK V2 
GPIOL6_TXD1_VPB0 W1 
GPIOL7_RXD1_VPB1 U5 
GPIOM0_NCTS2_VPB2 V3 
GPIOM1_NDCD2_VPB3 W2 
GPIOM2_NDSR2_VPB4 Y1 
GPIOM3_NRI2_VPB5 V4 
GPIOM4_NDTR2_VPB6 W3 
GPIOM5_NRTS2_VPB7 Y2 
GPIOM6_TXD2_VPB8 AA1 
GPIOM7_RXD2_VPB9 V5 
GPIOE0_NCTS3 D15 
GPIOE1_NDCD3 C15 
GPIOE2_NDSR3 B15 
GPIOE3_NRI3 A15 
GPIOE4_NDTR3 E14 
GPIOE5_NRTS3 D14 
GPIOE6_TXD3 C14 
GPIOE7_RXD3 B14 
GPIOF0_NCTS4 D18 
GPIOF1_NDCD4 B19 
GPIOF2_NDSR4 A20 
GPIOF3_NRI4 D17 
GPIOF4_NDTR4 B18 
GPIOF5_NRTS4 A19 
GPIOF6_TXD4 E16 
GPIOF7_RXD4 C17 
RXD5 G1 TXD5 H5 
RGMII1TXD3_RMII3TXD1 A13 RGMII1TXD2_RMII3TXD0 E12 
RGMII1TXD1_RMII1TXD1 D12 RGMII1TXD0_RMII1TXD0 C12 RGMII1TXCTL_RMII3TXEN B12 RGMII1TXCK_RMII1TXEN A12 
RGMII1RXCK_RMII1RCLK E11 RGMII1RXCTL_RMII3RCLK D11 
RGMII1RXD0_RMII1RXD0 C11 
RGMII1RXD1_RMII1RXD1 B11 
RGMII1RXD2_RMII1CRSDV A11 
RGMII1RXD3_RMII1RXER E10 
RGMII2TXD3_RMII4TXD1 D10 RGMII2TXD2_RMII4TXD0 C10 
RGMII2TXD1_RMII2TXD1 B10 RGMII2TXD0_RMII2TXD0 A10 RGMII2TXCTL_RMII4TXEN E9 RGMII2TXCK_RMII2TXEN D9 
RGMII2RXCK_RMII2RCLK C9 RGMII2RXCTL_RMII4RCLK B9 
RGMII2RXD0_RMII2RXD0 A9 
RGMII2RXD1_RMII2RXD1 E8 
RGMII2RXD2_RMII2CRSDV D8 
RGMII2RXD3_RMII2RXER C8 
RGMIICK B8 
GPIOR6_MDC1 C6 
GPIOR7_MDIO1 A5 
GPIOA6_TIMER7_MDC2 A3 
GPIOA7_TIMER8_MDIO2 D5 
GPIOI0_SYSCS# C22 
GPIOI1_SYSCK G18 
GPIOI2_SYSDO D19 
GPIOI3_SYSDI C20 
GPIOI4_SPICS#_VBCS# B22 
GPIOI5_SPICK_VBCK G19 
GPIOI6_SPIDO_VBDO C18 
GPIOI7_SPIDI_VBDI E20 
GPIOJ0_SGPMCK_MDC3 J5 
GPIOJ1_SGPMLD_MDIO3 J4 
GPIOJ2_SGPMO_MDC4 K5 
GPIOJ3_SGPMI_MDIO4 J3 



5
5
4
4
3
3
2
2
1
1
D D
C C
B B
A A
FOR BMC 
VGA OLNY 
BMC_NODE1_CLK_24M 
BMC_NODE1_USBVREF 
BMC_NODE1_OSC1_VDD 
BMC_NODE1_OSC1_EN 
BMC_NODE1_CLK_24M_R 
BMC_NODE1_JTAG_TRST 
BMC_NODE1_CLK_24M 
FM_BMC_NODE1_RESET_L 
BMC_NODE1_JTAG_TDI 
BMC_NODE1_JTAG_TMS 
BMC_NODE1_JTAG_TCK 
BMC_NODE1_GFX_HSYNC_R 
BMC_NODE1_GFX_VSYNC_R 
BMC_NODE1_GFX_HSYNC_R 
BMC_NODE1_GFX_VSYNC_R 
FM_BMC_NODE1_RESET_L (33,67) 
BMC_NODE1_GFX_BLUE (54) 
BMC_NODE1_GFX_GREEN (54) 
BMC_NODE1_GFX_RED (54) 
SMB_BMC_NODE1_DDC_CLK (54) 
SMB_BMC_NODE1_DDC_DAT (54) 
BMC_NODE1_GFX_HSYNC 
BMC_NODE1_GFX_VSYNC (54) 
P3V3_NODE1 
P3V3_NODE1 
P3V3_NODE1 
Title 
Size Document Number Rev
Date: Sheet 
of 
Node1 AST1300 GPIO JTAG MIS 1A
Chassis Manager Assembly V1 
Cloud Server Infrastructure Engineering
C
35 85Monday, January 27, 2014 
Title 
Size Document Number Rev
Date: Sheet 
of 
Node1 AST1300 GPIO JTAG MIS 1A
Chassis Manager Assembly V1 
Cloud Server Infrastructure Engineering
C
35 85Monday, January 27, 2014 
Title 
Size Document Number Rev
Date: Sheet 
of 
Node1 AST1300 GPIO JTAG MIS 1A
Chassis Manager Assembly V1 
Cloud Server Infrastructure Engineering
C
35 85Monday, January 27, 2014 
TP5 
NI 
1
R291 150 
1% R0402 
NI 
R312 22 
1% R0402 
NI 
C247 
0.1UF 
X7R 
C0402 
10% 
16V 
NI 
TP8 
NI 
1
R300 47K R0402 1% NI 
VGA 
USB 
PECI 
FAN 
ADC 
JTAG 
GPIO 
MISC 
U14C 
AST1300A1-GP 
NI 
ENTEST1 E4 
ENTEST2 K20 
CLKIN AB22 
SRST# W20 
DACB R4 
DACG R3 
DACR R2 
DDCCLK_GPIOJ6 T2 
DDCDAT_GPIOJ7 T1 
VGAHS_GPIOJ4 T4 
VGAVS_GPIOJ5 U2 
GPIOO0_TACH0_VPG8 V6 
GPIOO1_TACH1_VPG9 Y5 
GPIOO2_TACH2_VPR0 AA4 
GPIOO3_TACH3_VPR1 AB3 
GPIOO4_TACH4_VPR2 W6 
GPIOO5_TACH5_VPR3 AA5 
GPIOO6_TACH6_VPR4 AB4 
GPIOO7_TACH7_VPR5 V7 
GPION4_PWM4_VPG4 W5 
GPION5_PWM5_VPG5 Y4 
GPION6_PWM6_VPG6 AA3 
GPION7_PWM7_VPG7 AB2 
USB2AV33 W18 
USB2AVSS Y19 USB2VRES AA20 
USB2_DP AB21 
USB2_DN AB20 
USB11_HDN J2 USB11_HDP J1 
USB11_DP/USB11_HDP2 K4 
USB11_DN/USB11_HDN2 K3 
PECI AA21 PECIVDD V19 
ADC0 L5 
ADC1 L4 
ADC2 L3 
ADC3 L2 
ADC4 L1 
ADC5 M5 
ADC6 M4 
ADC7 M3 
ADC8 M2 
ADC9 M1 
ADC10 N5 
ADC11 N4 
ADC12P N3 
ADC13P N2 
ADC13N N1 
ADC12N P5 
NTRST E1 
TDI F1 
TMS G2 
TCK F2 
RTCK G4 
TDO G3 
GPIOG0_SGPSCK A14 
GPIOG1_SGPSLD E13 
GPIOG2_SGPSI0 D13 
GPIOG3_SGPSI1 C13 
GPIOG5_WDTRST2 Y21 
GPIOG6_FLBUSY# AA22 
GPIOG7_FLWP# U18 
GPIOG4_WDTRST1_OSCCLK B13 
GPIOA0_MAC1LINK D6 
GPIOA1_MAC2LINK B5 
GPIOA2_MAC3LINK A4 
GPIOA3_MAC4LINK E6 
GPIOB4_LPCRST# E19 
GPIOB5_LPCPD# H19 
GPIOB6_LPCPME# H20 
GPIOB7_EXTRST# E18 
GPIOP0_TACH8_VPR6 Y6 
GPIOP1_TACH9_VPR7 AB5 
GPIOP2_TACH10_VPR8 W7 
GPIOP3_TACH11_VPR9 AA6 
GPIOP4_TACH12 AB6 
GPIOP5_TACH13 Y7 
GPIOP6_TACH14 AA7 
GPIOP7_TACH15_FLACK AB7 
GPION0_PWM0_VPG0 W4 
GPION1_PWM1_VPG1 Y3 
GPION2_PWM2_VPG2 AA2 
GPION3_PWM3_VPG3 AB1 
C243 
100PF 50V 
C0402 
NPO 
5% NI 
C242 
1UF 10V 
C0402 
X5R 
10% NI 
C244 
0.1UF 16V 
C0402 
X7R 
10% NI 
TP6 
NI 
1
R290 150 
1% R0402 
NI 
R302 47K R0402 1% NI 
L13 
220/2000MA 
NI 
2 1
R311 
4.7K 
5% 
R0402 
NI 
R670 33 
R0402 
NI 
R294 8.2K 
1% R0402 
NI 
C246 
1UF 
X5R 
10V 
10% 
C0402 
NI 
R675 33 
R0402 
NI 
OSC3 
24MHZ 
NI 
OE 1 GND 2
OUT 3VDD 4
TP7 
NI 
1
R304 47K R0402 1% NI 
R293 10K 
1% R0402 
NI 
R298 47K R0402 1% NI 
R292 150 
1% R0402 
NI 



5
5
4
4
3
3
2
2
1
1
D D
C C
B B
A A
220ohm@100MHz 
 / 1000mA 
V1PLLAV12 
ADCAV33 
220ohm@100MHz 
 / 1000mA 
220ohm@100MHz 
 / 1000mA 
220ohm@100MHz 
 / 1000mA 
DACAV33 HPLLAV33 
AST1300_POWER 
IVD1 IVD2 IVD3 IVD4 
MVD1 MVD2 
PVD1 PVD2 PVD3 PVD4 
MPLLAV33 
Place under BGA 
at least 5 power vias (18mil) 
Place under BGA 
PEDV18 
PEAV18 
220ohm@100MHz 
 / 1000mA 
220ohm@100MHz 
 / 1000mA 
VGA OLNY 
BMC_NODE1_VCC_1V8_PCIE 
BMC_NODE1_V1PLLAV12 
BMC_NODE1_ADCAV33 
BMC_NODE1_V1PLLAV12 
BMC_NODE1_DACAV33 
BMC_NODE1_VCC_1V8_PCIEA 
BMC_NODE1_ADCAV33 
BMC_NODE1_ADCREXT 
BMC_NODE1_DACAV33 
BMC_NODE1_MPLLAV33 
TP_BMC_NODE1_ADCVREFN 
BMC_NODE1_HPLLAV33 
BMC_NODE1_MPLLAV33 
BMC_NODE1_VCC_1V8_PCIE 
TP_BMC_NODE1_ADCVREFP 
BMC_NODE1_DACRSET 
BMC_NODE1_HPLLAV33 
BMC_NODE1_VCC_1V8_PCIEA 
BMC_NODE1_HPLLAV33 
BMC_NODE1_MPLLAV33 
BMC_NODE1_DACAV33 
P1V26_BMC_NODE1 
P1V26_BMC_NODE1 
P3V3_NODE1 
P3V3_NODE1 
P3V3_NODE1 
P3V3_NODE1 
P3V3_NODE1 
P1V538_BMC_NODE1 
P3V3_NODE1 
P1V26_BMC_NODE1 
P1V538_BMC_NODE1 
P3V3_NODE1 
P3V3_NODE1 
P1V26_BMC_NODE1 
P1V8_NODE1 
P1V8_NODE1 
Title 
Size Document Number Rev
Date: Sheet 
of 
Node1 AST1300 Power 1A
Chassis Manager Assembly V1 
Cloud Server Infrastructure Engineering
C
36 85Monday, January 27, 2014 
Title 
Size Document Number Rev
Date: Sheet 
of 
Node1 AST1300 Power 1A
Chassis Manager Assembly V1 
Cloud Server Infrastructure Engineering
C
36 85Monday, January 27, 2014 
Title 
Size Document Number Rev
Date: Sheet 
of 
Node1 AST1300 Power 1A
Chassis Manager Assembly V1 
Cloud Server Infrastructure Engineering
C
36 85Monday, January 27, 2014 
C281 
1UF 
X5R 
10% 
10V 
C0402 
NI 
L19 
220/2000MA 
NI 
2 1
C263 
1UF 
X5R 
C0402 
10% 
10V NI 
L15 
220/2000MA 
NI 
2 1
C273 
0.01UF 
C0402 
16V 
10% 
X7R NI 
U14D 
AST1300A1-GP 
NI 
GND_1 J10 
GND_2 J11 
GND_3 J12 
GND_4 J13 
GND_5 J14 
GND_6 J9 
GND_7 K10 
GND_8 K11 
GND_9 K12 
GND_10 K13 
GND_11 K14 
GND_12 K9 
GND_13 L10 
GND_14 L11 
GND_15 L12 
GND_16 L13 
GND_17 L14 
GND_18 L9 
GND_19 M10 
GND_20 M11 
GND_21 M12 
GND_22 M13 
GND_23 M14 
GND_24 M9 
GND_25 N10 
GND_26 N11 
GND_27 N12 
GND_28 N13 
GND_29 N14 
GND_30 N9 
GND_31 P10 
GND_32 P11 
GND_33 P12 
GND_34 P13 
GND_35 P14 
GND_36 P9 
R2VDD_1 F8 
R2VDD_2 F9 
R1VDD_1 F10 
R1VDD_2 F11 
MVDD_1 U10 
MVDD_2 U11 
MVDD_3 U14 
MVDD_4 U15 
PV33D_1 F12 
PV33D_2 F13 
PV33D_3 H6 
PV33D_4 H17 
PV33D_5 J6 
PV33D_6 J17 
PV33D_7 M6 
PV33D_8 M17 
PV33D_9 N6 
PV33D_10 N17 
PV33D_11 U8 
PV33D_12 U9 
IV12D_1 F14 
IV12D_2 F15 
IV12D_3 K6 
IV12D_4 K17 
IV12D_5 L6 
IV12D_6 L17 
IV12D_7 P6 
IV12D_8 P17 
IV12D_9 R6 
IV12D_10 R17 
IV12D_11 U12 
IV12D_12 U13 
MPLLAV33 AB19 
HPLLAV33 V17 
MPLLDV12 Y18 
V1PLLAV12 W19 
V2PLLAV12 Y20 
PLLVSS_1 AA19 
PLLVSS_2 AA18 
PLLVSS_3 V18 
DACAV33 P1 
DACAVSS R5 
DACRSET R1 
DACDV33 T3 
ADCVREFN K2 
ADCVREFP K1 
ADCAVSS P4 
ADCAV33 P3 
ADCREXT P2 
PEPLLAV18 F20 
PEAV18 C21 
PEDV18_1 G20 
PEDV18_2 H21 
PEDV18_3 H22 
PEAGND_1 D21 
PEAGND_2 D22 
C276 
10UF 10V 
20% 
X5R 
C0603 
NI 
C289 
1UF 
X5R 
C0402 
10% 
10V NI 
C279 
1UF 
X5R 
10% 
C0402 
10V 
NI 
C265 
1UF 
X5R 
C0402 
10% 
10V NI 
C272 
1UF 
X5R 
C0402 
10% 
10V 
NI 
C297 
100PF 
NPO 
C0402 
5% 
50V NI 
C269 
1UF 
X5R 
10% 
C0402 
10V NI 
C250 
0.1UF 16V 
10% 
C0402 
X7R 
NI 
C258 
100PF 
NPO 
C0402 
5% 
50V NI 
C280 
0.1UF 10% 
C0402 
X7R 
16V 
NI 
C295 
1UF 
X5R 
C0402 
10% 
10V NI 
C286 
10UF 
X5R 
C0603 
20% 
6.3V NI 
C255 
0.47UF 10V 
10% 
C0402 
X5R 
NI 
C284 
1UF 10V 
10% 
C0402 
X5R 
NI 
C275 
0.01UF 
C0402 
16V 
10% 
X7R NI 
C287 
1UF 
X5R 
C0402 
10% 
10V NI 
C292 
0.1UF 
X7R 
C0402 
10% 
16V NI 
C262 
4.7UF 
X5R 
C0603 
20% 
6.3V NI 
L18 
220/2000MA 
NI 
2 1
C257 
1UF 
X5R 
C0402 
10% 
10V NI 
C278 
0.1UF 
X7R 
C0402 
10% 
16V NI 
C288 
0.1UF 
X7R 
C0402 
10% 
16V NI 
C248 
10UF 6.3V 
20% 
C0603 
X5R 
NI 
C249 
0.47UF 10V 
10% 
C0402 
X5R 
NI 
C282 
0.1UF 
C0402 
X7R 
10% 
16V NI 
C296 
0.1UF 
X7R 
C0402 
10% 
16V NI 
C293 
1UF 
X5R 
C0402 
10% 
10V NI 
C267 
100PF 
NPO 
C0402 
5% 
50V NI 
C256 
0.1UF 16V 
10% 
C0402 
X7R 
NI 
R314 
0
5% 
R0603 
NI 
L16 
220/2000MA 
NI 
2 1
C271 
10UF 
X5R 
C0603 
20% 
6.3V 
NI 
C270 
100PF 
NPO 
5% 
C0402 
50V NI 
C266 
0.1UF 
X7R 
C0402 
10% 
16V NI 
C290 
0.1UF 
X7R 
C0402 
10% 
16V NI 
C285 
0.1UF 
X7R 
C0402 
10% 
16V NI 
C274 
1UF 
X5R 
C0402 
10% 
10V 
NI 
C253 
0.47UF 10V 
10% 
C0402 
X5R 
NI 
C294 
0.1UF 
X7R 
C0402 
10% 
16V NI 
C277 
1UF 10V 
10% 
C0402 
X5R 
NI 
C291 
0.47UF 
X5R 
C0402 
10% 
10V NI 
C254 
0.1UF 16V 
10% 
C0402 
X7R 
NI 
C283 
10UF 10V 
20% 
X5R 
C0603 
NI 
C251 
0.47UF 10V 
10% 
C0402 
X5R 
NI 
C268 
0.1UF 
X7R 
10% 
C0402 
16V NI 
R313 49.9K 
1% R0402 
NI 
R315 2.74K 
R0603 1% 
NI 
C264 
100PF 
NPO 
C0402 
5% 
50V NI 
C252 
0.1UF 16V 
10% 
C0402 
X7R 
NI 
L14 
220/2000MA 
NI 
2 1
L17 
220/2000MA 
NI 
2 1



5
5
4
4
3
3
2
2
1
1
D D
C C
B B
A A
ROMA[1:0] : Coprocessor boot code s 
 00 : Boot from NOR flash memory 
 01 : Boot from NAND flash memory 
 10 : Boot from SPI flash memory 
*11 : Disable CPU operation (Select) 
ROMA[3:2] : VGA memory size selection 
 00 : Select 8  MB VGA memory 
 01 : Select 16 MB VGA memory 
 10 : Select 32 MB VGA memory 
*11 : Select 64 MB VGA memory (Select) 
ROMA[5] : Enable VGA BIOS ROM (depends on design) 
0 : No VGA BIOS ROM (for on-board application) 
1 : Enable VGA BIOS ROM (for add-on application) 
ROMA[9:8] : H-PLL default clock frequency selection
00: Select 384 MHz 
01: Select 360 MHz 
10: Select 336 MHz (Select) 
11: Select 408 MHz 
ROMA[11:10] : CPU/AHB clock frequency ratio selection 
00 : Select CPU:AHB = 1:1 
01 : Select CPU:AHB = 2:1 
10 : Select CPU:AHB = 4:1 (Select) 
11 : Select CPU:AHB = 3:1 
ROMA[15] : VGA Class Code selection 
0 : Select the Class Code for video device 
1 : Select the Class Code for VGA device (Select) 
ROMA[19] : Disable MSI controller 
0 : Enable 
1 : Disable (Select) 
ROMA[20] : Disable LPC to decode SuperIO 0x2E/0x4E address 
0 : Enable address decoding 
1 : Disable address decoding (Select) 
AST1300 DON'T DEFINE 
ROMD[2:0] : DRAM configuration setting 
000: DDR3 SDRAM with CL = 5, CWL = 5 
010: DDR3 SDRAM with CL = 6, CWL = 5 (Select) 
100: DDR3 SDRAM with CL = 7, CWL = 6 
110: DDR3 SDRAM with CL = 8, CWL = 6 
001: DDR2 SDRAM with CL = 4 
011: DDR2 SDRAM with CL = 5 
101: DDR2 SDRAM with CL = 6 
111: DDR2 SDRAM with CL = 7 
The DRAM configuration setting is defined for 
compliant VGA BIOS/Driver and BMC firmware 
default supported DRAM timing. The trapping 
setting must meet the DRAM speed bin used to 
get correct DRAM timing in itialization. 
ROMD[4:3] : DRAM size setting 
00:  64 MBytes 
01: 128 MBytes (Select) 
10: 256 MBytes 
11: 512 MBytes 
BMC_ROMA1 
BMC_ROMA0 
BMC_ROMA2 
BMC_ROMA3 
BMC_ROMA4 
BMC_ROMA5 
BMC_ROMA7 
BMC_ROMA6 
BMC_ROMA9 
BMC_ROMA8 
BMC_ROMA11 
BMC_ROMA10 
BMC_ROMA13 
BMC_ROMA14 
BMC_ROMA12 
BMC_ROMA15 
BMC_ROMA17 
BMC_ROMA16 
BMC_ROMA18 
BMC_ROMA19 
BMC_ROMA20 
BMC_ROMA21 
BMC_ROMA22 
BMC_ROMA23 
BMC_ROMD3 
BMC_ROMD1 
BMC_ROMD0 
BMC_ROMD2 
BMC_ROMD4 
P3V3_NODE1 
P3V3_NODE1 
P3V3_NODE1 
P3V3_NODE1 
P3V3_NODE1 
P3V3_NODE1 
P3V3_NODE1 
P3V3_NODE1 
P3V3_NODE1 
P3V3_NODE1 
P3V3_NODE1 
Title 
Size Document Number Rev
Date: Sheet 
of 
Node1 AST1300 HW Strapping 1A
Chassis Manager Assembly V1 
Cloud Server Infrastructure Engineering
C
37 85Monday, January 27, 2014 
Title 
Size Document Number Rev
Date: Sheet 
of 
Node1 AST1300 HW Strapping 1A
Chassis Manager Assembly V1 
Cloud Server Infrastructure Engineering
C
37 85Monday, January 27, 2014 
Title 
Size Document Number Rev
Date: Sheet 
of 
Node1 AST1300 HW Strapping 1A
Chassis Manager Assembly V1 
Cloud Server Infrastructure Engineering
C
37 85Monday, January 27, 2014 
R341 4.7K 
5% R0402 
NI 
R330 4.7K NI 
5% R0402 
R326 4.7K 
5% R0402 
NI 
R340 4.7K NI 
5% R0402 
R328 4.7K 
5% R0402 
NI 
R317 4.7K 
5% R0402 
NI 
R333 4.7K NI 
5% R0402 
R339 4.7K 
5% R0402 
NI 
R331 4.7K 
5% R0402 
NI 
R327 4.7K 
5% R0402 
NI 
R316 4.7K NI 
5% R0402 
R338 4.7K NI 
5% R0402 
R334 4.7K NI 
5% R0402 
R343 4.7K 
5% R0402 
NI 
R337 4.7K NI 
5% R0402 
R332 4.7K NI 
5% R0402 
R335 4.7K 
5% R0402 
NI 
R323 4.7K 
5% R0402 
NI 
R319 4.7K 
5% R0402 
NI 
R322 4.7K 
5% R0402 
NI 
R318 4.7K 
5% R0402 
NI 
R321 4.7K NI 
5% R0402 
R342 4.7K NI 
5% R0402 
R325 4.7K 
5% R0402 
NI 
R344 4.7K NI 
5% R0402 
R336 4.7K 
5% R0402 
NI 
R320 4.7K NI 
5% R0402 
R329 4.7K NI 
5% R0402 
R324 4.7K 
5% R0402 
NI 



5
5
4
4
3
3
2
2
1
1
D D
C C
B B
A A
Title 
Size Document Number Rev
Date: Sheet 
of 
Blank 1A
Chassis Manager Assembly V1 
Cloud Server Infrastructure Engineering
C
38 85Monday, January 27, 2014 
Title 
Size Document Number Rev
Date: Sheet 
of 
Blank 1A
Chassis Manager Assembly V1 
Cloud Server Infrastructure Engineering
C
38 85Monday, January 27, 2014 
Title 
Size Document Number Rev
Date: Sheet 
of 
Blank 1A
Chassis Manager Assembly V1 
Cloud Server Infrastructure Engineering
C
38 85Monday, January 27, 2014 



5
5
4
4
3
3
2
2
1
1
D D
C C
B B
A A
Title 
Size Document Number Rev
Date: Sheet 
of 
Blank 1A
Chassis Manager Assembly V1 
Cloud Server Infrastructure Engineering
C
39 85Monday, January 27, 2014 
Title 
Size Document Number Rev
Date: Sheet 
of 
Blank 1A
Chassis Manager Assembly V1 
Cloud Server Infrastructure Engineering
C
39 85Monday, January 27, 2014 
Title 
Size Document Number Rev
Date: Sheet 
of 
Blank 1A
Chassis Manager Assembly V1 
Cloud Server Infrastructure Engineering
C
39 85Monday, January 27, 2014 



5
5
4
4
3
3
2
2
1
1
D D
C C
B B
A A
Title 
Size Document Number Rev
Date: Sheet 
of 
Blank 1A
Chassis Manager Assembly V1 
Cloud Server Infrastructure Engineering
C
40 85Monday, January 27, 2014 
Title 
Size Document Number Rev
Date: Sheet 
of 
Blank 1A
Chassis Manager Assembly V1 
Cloud Server Infrastructure Engineering
C
40 85Monday, January 27, 2014 
Title 
Size Document Number Rev
Date: Sheet 
of 
Blank 1A
Chassis Manager Assembly V1 
Cloud Server Infrastructure Engineering
C
40 85Monday, January 27, 2014 



5
5
4
4
3
3
2
2
1
1
D D
C C
B B
A A
Title 
Size Document Number Rev
Date: Sheet 
of 
Blank 1A
Chassis Manager Assembly V1 
Cloud Server Infrastructure Engineering
C
41 85Monday, January 27, 2014 
Title 
Size Document Number Rev
Date: Sheet 
of 
Blank 1A
Chassis Manager Assembly V1 
Cloud Server Infrastructure Engineering
C
41 85Monday, January 27, 2014 
Title 
Size Document Number Rev
Date: Sheet 
of 
Blank 1A
Chassis Manager Assembly V1 
Cloud Server Infrastructure Engineering
C
41 85Monday, January 27, 2014 



5
5
4
4
3
3
2
2
1
1
D D
C C
B B
A A
Title 
Size Document Number Rev
Date: Sheet 
of 
Blank 1A
Chassis Manager Assembly V1 
Cloud Server Infrastructure Engineering
C
42 85Monday, January 27, 2014 
Title 
Size Document Number Rev
Date: Sheet 
of 
Blank 1A
Chassis Manager Assembly V1 
Cloud Server Infrastructure Engineering
C
42 85Monday, January 27, 2014 
Title 
Size Document Number Rev
Date: Sheet 
of 
Blank 1A
Chassis Manager Assembly V1 
Cloud Server Infrastructure Engineering
C
42 85Monday, January 27, 2014 



5
5
4
4
3
3
2
2
1
1
D D
C C
B B
A A
Title 
Size Document Number Rev
Date: Sheet 
of 
Blank 1A
Chassis Manager Assembly V1 
Cloud Server Infrastructure Engineering
C
43 85Monday, January 27, 2014 
Title 
Size Document Number Rev
Date: Sheet 
of 
Blank 1A
Chassis Manager Assembly V1 
Cloud Server Infrastructure Engineering
C
43 85Monday, January 27, 2014 
Title 
Size Document Number Rev
Date: Sheet 
of 
Blank 1A
Chassis Manager Assembly V1 
Cloud Server Infrastructure Engineering
C
43 85Monday, January 27, 2014 



5
5
4
4
3
3
2
2
1
1
D D
C C
B B
A A
Title 
Size Document Number Rev
Date: Sheet 
of 
Blank 1A
Chassis Manager Assembly V1 
Cloud Server Infrastructure Engineering
C
44 85Monday, January 27, 2014 
Title 
Size Document Number Rev
Date: Sheet 
of 
Blank 1A
Chassis Manager Assembly V1 
Cloud Server Infrastructure Engineering
C
44 85Monday, January 27, 2014 
Title 
Size Document Number Rev
Date: Sheet 
of 
Blank 1A
Chassis Manager Assembly V1 
Cloud Server Infrastructure Engineering
C
44 85Monday, January 27, 2014 



5
5
4
4
3
3
2
2
1
1
D D
C C
B B
A A
SATA_SPI_DI_NODE1_R 
IRQ_LVC3_SATA_NODE1_WAKE_L 
TP_SATA_NODE1 
P2E_CPU_SATA_NODE1_TX_DP 
SATA_SPI_CS_NODE1 
P2E_CPU_SATA_NODE1_RX_DN 
P2E_CPU_SATA_NODE1_RX_DP 
SATA_NODE1_ISET 
SATA_NODE1_GPIO1 
SATA_NODE1_GPIO2 
SATA_NODE1_GPIO3 
CLK_25M_SATA_NODE1 
FM_CPLD_NODE1_SATA_PERST_L 
SATA_NODE1_XTLOUT 
SATA_NODE1_GPIO5 
CLK_100M_SATA_NODE1_DP 
SATA_NODE1_GPIO5 
SATA_SPI_DI_NODE1 
P2E_CPU_SATA_NODE1_TX_DN 
PU_SATA_NODE1_GPIO4 
P2E_CPU_SATA_NODE1_RX_C_DN 
LED_SATA_NODE1_R 
CLK_100M_SATA_NODE1_DN 
SATA_VCONT_NODE1 
NODE1_USB_TESTMODE 
SATA_SPI_CLK_NODE1 
P2E_CPU_SATA_NODE1_RX_C_DP 
LED_SATA_NODE1_GPIO0 
SATA_NODE1_GPIO1 
SATA_NODE1_GPIO3 
SATA_NODE1_GPIO2 
SATA_SPI_DO_NODE1 
SATA_SPI_CLK_NODE1_R 
SATA_SPI_CS_NODE1_R 
SATA_SPI_CLK_NODE1 
SATA_SPI_DO_NODE1 
SATA_SPI_CS_NODE1 
SATA_SPI_DO_NODE1_R 
SATA_SPI_CS_NODE1_R 
SATA_SPI_CLK_NODE1_R 
SATA_SPI_DI_NODE1 
SATA_SPI_DO_NODE1_R 
PU_SATA_NODE1_GPIO4 
CLK_25M_SATA_NODE1 
SATA_A_NODE1_RX_N0 
SATA_A_NODE1_RX_P0 
P2E_CPU_SATA_NODE1_RX_DN (15) 
P2E_CPU_SATA_NODE1_RX_DP (15) 
CLK_100M_SATA_NODE1_DP 
CLK_100M_SATA_NODE1_DN 
P2E_CPU_SATA_NODE1_TX_DN 
P2E_CPU_SATA_NODE1_TX_DP 
SATA_A_NODE1_TX_N0 (54) 
SATA_A_NODE1_TX_P0 (54) 
FM_CPLD_NODE1_SATA_PERST_L (67) 
IRQ_LVC3_CPU_NODE1_WAKE_L (19,30,67) 
P1V0_SATA 
P3V3_NODE1 
P1V8_SATA_AVDD_NODE1 
P1V8_SATA_VAA1_NODE1 
P1V8_SATA_VAA2_0_NODE1 
P1V8_SATA_VAA2_1_NODE1 
P1V0_SATA 
P3V3_NODE1 
P3V3_NODE1 
P3V3_NODE1 
P3V3_NODE1 
P1V8_NODE1 
P3V3_NODE1 
P3V3_NODE1 
P3V3_NODE1 
P3V3_NODE1 
P1V0_NODE1 P1V0_SATA 
P3V3_NODE1 
Title 
Size Document Number Rev
Date: Sheet 
of 
Node1 HDD Controller 1 1A
Chassis Manager Assembly V1 
Cloud Server Infrastructure Engineering
C
45 85Monday, January 27, 2014 
Title 
Size Document Number Rev
Date: Sheet 
of 
Node1 HDD Controller 1 1A
Chassis Manager Assembly V1 
Cloud Server Infrastructure Engineering
C
45 85Monday, January 27, 2014 
Title 
Size Document Number Rev
Date: Sheet 
of 
Node1 HDD Controller 1 1A
Chassis Manager Assembly V1 
Cloud Server Infrastructure Engineering
C
45 85Monday, January 27, 2014 
R505 
10K 
1% 
R0402 
R804 0
R0805 
C334 
0.1UF 
X7R 
16V 
C0402 
R502 4.7K 
5% R0402 
NI 
R517 4.7K 5% R0402 NI 
R501 
330 
5% 
R0402 
NI 
R509 4.7K 5% R0402 NI C333 0.1UF 
X7R 
C0402 
10% 
16V 
R653 4.7K 
5% R0402 
C329 
1UF 10% 
X5R 
C0603 
16V 
U31 
W25X40BVSSIG 
CS# 1
WP# 3
HOLD# 7
SI 5
SCK 6
VCC 8
SO 2
GND 4
R508 33 
R0402 1% 
R504 
6.04K 
1% 
R0402 
C335 
0.1UF 
X7R 
16V 
C0402 
R510 4.7K 5% R0402 NI 
R506 33 
R0402 1% 
R511 4.7K 5% R0402 NI 
R519 33 
R0402 1% 
Q12 
PBSS5140T 
NI 
23
1
R507 33 
R0402 1% 
C332 0.1UF 
X7R 
C0402 
10% 
16V 
R516 
4.7K 
5% 
R0402 
U30 
88SE9130B1-NAA2C000 
VDD_1 5
VDD_2 13 
VDD_3 21 
VDD_4 51 
VDD_5 64 
VDD_6 71 
VDDIO_1 9
VDDIO_2 57 
VDDIO_3 73 
AVDDT 41 
AVDD 42 
VAA1 34 
VAA2_0 31 
VAA2_1 25 
VCONT_10 38 
SPI_DI 49 
SPI_DO 47 
SPI_CS 48 
SPI_CLK 50 
RXN_0 30 
RXP_0 29 
RXN_1 24 
RXP_1 23 
TXN_0 32 
TXP_0 33 
TXN_1 26 
TXP_1 27 
PRXN 43 
PRXP 44 
PTXN 39 
PTXP 40 
CLKP 45 
CLKN 46 
PERST# 53 
WAKE# 52 
GPIO0 54 
GPIO1 74 
GPIO2 75 
GPIO3 17 
GPIO4 18 
GPIO5 19 
TP 22 
TESTMODE 20 
XTLIN_OSC 35 
XTLOUT 36 
ISET 37 
NC#1 1
NC#2 2
NC#3 3
NC#4 4
NC#6 6
NC#7 7
NC#8 8
NC#10 10 
NC#11 11 
NC#12 12 
NC#14 14 
NC#15 15 
NC#16 16 
NC#55 55 
NC#56 56 
NC#58 58 
NC#59 59 
NC#60 60 
NC#61 61 
NC#62 62 
NC#63 63 
NC#65 65 
NC#66 66 
NC#67 67 
NC#68 68 
NC#69 69 
NC#70 70 
NC#72 72 
NC#76 76 
VSS 28 
THERMAL_PAD TH 
R515 4.7K 5% R0402 NI 
R514 4.7K 5% R0402 NI 
R513 0
R0402 5% 
NI 
R512 4.7K 5% R0402 NI 
D5 
LED YEL/GR 
NI 
A C
R503 10K 
1% R0402 
R518 4.7K 5% R0402 NI 



5
5
4
4
3
3
2
2
1
1
D D
C C
B B
A A
Analog Power For PCIE PHY 
(20+35=55mA) 
Digital Core Power(900mA) 
Trace_widthh >40mil 
Analog Power For Crystal Oscillator 
And PLL(10mA) 
Trace_Width >20mil 
Trace_widthh >20mil 
Digital I/O Power(50mA) 
Trace_length >10mil 
Analog Power For SATA PHY (70mA) 
Trace_length >20mil 
Trace_length >20mil 
Analog Power For SATA PHY (70mA) 
P1V0_SATA 
P3V3_NODE1 
P1V8_NODE1 P1V8_SATA_AVDD_NODE1 
P1V8_NODE1 P1V8_SATA_VAA1_NODE1 
P1V8_NODE1 P1V8_SATA_VAA2_0_NODE1 
P1V8_NODE1 P1V8_SATA_VAA2_1_NODE1 
Title 
Size Document Number Rev
Date: Sheet 
of 
Node1 HDD Controller 2 1A
Chassis Manager Assembly V1 
Cloud Server Infrastructure Engineering
C
46 85Monday, January 27, 2014 
Title 
Size Document Number Rev
Date: Sheet 
of 
Node1 HDD Controller 2 1A
Chassis Manager Assembly V1 
Cloud Server Infrastructure Engineering
C
46 85Monday, January 27, 2014 
Title 
Size Document Number Rev
Date: Sheet 
of 
Node1 HDD Controller 2 1A
Chassis Manager Assembly V1 
Cloud Server Infrastructure Engineering
C
46 85Monday, January 27, 2014 
C359 
2.2UF 
X5R 
C0402 
20% 
6.3V 
C346 
1000PF 
X7R 
C0402 
5% 
50V 
C361 
0.01UF 16V 
10% 
C0402 
X7R 
C353 
0.1UF 
X7R 
C0402 
10% 
16V 
C348 
0.1UF 
X7R 
C0402 
10% 
16V 
C344 
0.1UF 
X7R 
C0402 
10% 
16V 
C354 
0.1UF 
X7R 
C0402 
10% 
16V 
C339 
0.1UF 
X7R 
C0402 
10% 
16V 
C360 
0.1UF 
X7R 
C0402 
10% 
16V 
C355 
2.2UF 
X5R 
C0402 
20% 
6.3V 
L30 
120/0.3A 
21
C358 
1000PF 
X7R 
C0402 
5% 
50V 
C350 
1000PF 
X7R 
C0402 
5% 
50V 
C357 
0.01UF 16V 
10% 
C0402 
X7R 
C342 
1000PF 
X7R 
C0402 
5% 
50V 
C349 
0.01UF 16V 
10% 
C0402 
X7R 
C356 
0.1UF 
X7R 
C0402 
10% 
16V 
C351 
2.2UF 
X5R 
C0402 
20% 
6.3V 
C341 
0.1UF 
X7R 
C0402 
10% 
16V 
L31 
120/0.3A 
21
C338 
0.1UF 
X7R 
C0402 
10% 
16V 
L32 
120/0.3A 
21
C343 
2.2UF 
X5R 
C0402 
20% 
6.3V 
C340 
0.1UF 
X7R 
C0402 
10% 
16V 
C352 
0.1UF 
X7R 
C0402 
10% 
16V 
C336 
2.2UF 
X5R 
C0402 
20% 
6.3V 
L33 
120/0.3A 
21
C347 
2.2UF 
X5R 
C0402 
20% 
6.3V 
C362 
1000PF 
X7R 
C0402 
5% 
50V 
C337 
0.1UF 
X7R 
C0402 
10% 
16V 
C345 
0.01UF 16V 
10% 
C0402 
X7R 



5
5
4
4
3
3
2
2
1
1
D D
C C
B B
A A
VDD10 line (412mA) 
VDD33 line (100mA) 
AVDD33 line (10mA) 
P2E_CPU_USB_NODE1_RX_C_DN 
P2E_CPU_USB_NODE1_RX_C_DP 
P2E_CPU_USB_NODE1_RX_C_DP 
P2E_CPU_USB_NODE1_RX_C_DN 
USB_WAKE_N 
USB_WAKE_N 
USB_NODE1_PECREQ_L 
SPI_USB_NODE1_CLK 
SPI_USB_NODE1_CSB_N 
SPI_USB_NODE1_SO SPI_USB_NODE1_R_SO 
SPI_USB_NODE1_CLK_R 
SPI_USB_NODE1_CSB_R_L 
SPI_USB_NODE1_SI 
USB_NODE1_XTA1 
USB_NODE1_XTA2 
USB_NODE1_XTA1 
USB_NODE1_XTA2 
USB_NODE1_RREF 
USB_NODE1_RREF 
USB_OC_PU 
USB_OC_PU 
TP_U3TXDN1 
TP_U3TXDP1 
TP_U3TXDN2 
TP_U3TXDP2 
TP_U3TXDN3 
TP_U3TXDP3 
TP_U3TXDN4 
TP_U3TXDP4 
SPI_USB_NODE1_HOLD_L 
SPI_USB_NODE1_SI_R 
SPI_USB_NODE1_CSB_N 
SPI_USB_NODE1_SI SPI_USB_NODE1_SO 
SPI_USB_NODE1_CLK 
SPI_USB_NODE1_WP_L 
USB_NODE1_PECREQ_L 
USB_WAKE_N 
CLK_100M_USB_NODE1_DN (13) 
CLK_100M_USB_NODE1_DP (13) 
P2E_CPU_USB_NODE1_RX_DP (30) 
P2E_CPU_USB_NODE1_RX_DN (30) 
P2E_CPU_USB_NODE1_TX_DN 
P2E_CPU_USB_NODE1_TX_DP 
IRQ_LVC3_CPU_NODE1_WAKE_L (19,30,67) 
USB_NODE1_SMI_L (16) 
FM_CPLD_NODE1_USB_PONRST_L (67) 
USB_NODE1_SMI_L (16) 
FM_CPLD_NODE1_USB_PONRST_L 
USB0_DP (57) 
USB0_DN (57) 
USB1_DN (57) 
USB1_DP (57) 
USB2_DN (57) 
USB2_DP (57) 
USB3_DN (57) 
USB3_DP (57) 
PE_SW_USB_PERST_L 
FM_CPLD_NODE1_USB_PERST_L (67) 
P3V3_NODE1 
P3V3_USB_NODE1 
P3V3_NODE1 
P1V05_NODE1 
P3V3_NODE1 
P1V05_NODE1 
P3V3_NODE1 
P3V3_NODE1 
P3V3_NODE1 
P3V3_NODE1 
P3V3_USB_NODE1 P3V3_NODE1 
Title 
Size Document Number Rev
Date: Sheet 
of 
Node1 USB Controller 1A
Chassis Manager Assembly V1 
Cloud Server Infrastructure Engineering
C
47 85Monday, January 27, 2014 
Title 
Size Document Number Rev
Date: Sheet 
of 
Node1 USB Controller 1A
Chassis Manager Assembly V1 
Cloud Server Infrastructure Engineering
C
47 85Monday, January 27, 2014 
Title 
Size Document Number Rev
Date: Sheet 
of 
Node1 USB Controller 1A
Chassis Manager Assembly V1 
Cloud Server Infrastructure Engineering
C
47 85Monday, January 27, 2014 
R530 33 
R0402 1% 
NI 
Y3 
24MHZ 
NI 
C379 
0.01UF 16V 
10% 
C0402 
X7R 
NI 
R273 0 NI 
R526 1.6K 
1% R0402 
NI 
R527 10K 
R0402 1% 
NI 
C371 
0.01UF 16V 
10% 
C0402 
X7R 
NI 
R528 10K 
1% R0402 
NI 
R531 47K 
1% R0402 
NI 
C382 
0.01UF 16V 
10% 
C0402 
X7R 
NI 
R525 10K 
R0402 1% 
NI 
R524 33 R0402 1% NI 
C369 
0.1UF 
X7R 
16V 
10% 
C0402 
NI 
uPD720201 
U32 
UPD720201K8-701-BAC-A 
NI 
XT2 30 XT1 31 
PONRSTB 14 
PERSTB 2
PEWAKEB 3
PECREQB 13 
AVDD33_1 6
AVDD33_2 32 
PECLKN 5
PETXN 8
PERXP 10 
PERXN 11 
SPISCK 18 
SPICSB 17 
IC(L) 34 
VDD33_3 40 
VDD33_4 49 
VDD10_6 46 
VDD10_5 43 
VDD10_4 37 
VDD10_3 28 
VDD10_2 12 
VDD10_1 9
VDD33_1 15 
VDD33_2 29 
GND TH 
SPISI 19 
SPISO 16 
VDD10_7 54 
SMIB 1
RREF 33 
U3TXDP2 44 
U3TXDN2 45 
U3RXDP2 47 
U3RXDN2 48 
U2DP1 41 
U2DM1 42 
U3TXDP1 35 
U3TXDN1 36 
U3RXDP1 38 
U3RXDN1 39 
U2DP2 50 
U2DM2 51 
OCI2B 24 
OCI1B 26 
PPON2 25 
PPON1 27 
PETXP 7
PECLKP 4
VDD33_5 57 
VDD33_6 66 
VDD10_8 60 VDD10_9 63 
U3TXDP3 52 
U3TXDN3 53 
U2DP3 58 
U2DM3 59 
U3RXDP3 55 
U3RXDN3 56 
OCI3B 22 OCI4B 20 
PPON3 23 PPON4 21 
U3TXDP4 61 
U3TXDN4 62 
U2DP4 67 
U2DM4 68 
U3RXDP4 64 
U3RXDN4 65 
C383 
0.1UF 
X7R 
16V 
10% 
C0402 
NI 
R274 0 NI 
C381 
0.01UF 16V 
10% 
C0402 
X7R 
NI 
R523 33 R0402 1% NI 
R529 10K 
1% R0402 
NI 
C385 
0.1UF 
X7R 
16V 
10% 
C0402 
NI 
C376 
0.01UF 16V 
10% 
C0402 
X7R 
NI 
C363 0.1UF 
X7R 16V 
10% C0402 
NI 
C380 
0.01UF 16V 
10% 
C0402 
X7R 
NI 
R522 33 R0402 1% NI 
C368 
0.1UF 
X7R 
16V 
10% 
C0402 
NI 
C384 
0.01UF 16V 
10% 
C0402 
X7R 
NI 
C373 
0.01UF 16V 
10% 
C0402 
X7R 
NI 
C377 
0.1UF 
X7R 
16V 
10% 
C0402 
NI 
C364 0.1UF 
X7R 16V 
10% C0402 
NI 
C372 
0.01UF 16V 
10% 
C0402 
X7R 
NI 
L34 
60/3A 
NI 
21
R533 10K 
R0402 1% 
NI 
C378 
0.01UF 16V 
10% 
C0402 
X7R 
NI 
C386 
0.01UF 16V 
10% 
C0402 
X7R 
NI 
R534 10K 
R0402 1% 
NI 
U33 
MX25L5121EMC20G 
NI 
CS# 1
WP# 3
HOLD# 7
SI 5
SCK 6
VCC 8
SO 2
GND 4
C375 
0.01UF 16V 
10% 
C0402 
X7R 
NI 
C374 
0.01UF 16V 
10% 
C0402 
X7R 
NI 
C365 
15PF 
C0402 
5% 
50V 
NPO 
NI 
C370 
0.1UF 
X7R 
16V 
10% 
C0402 
NI 
C366 
15PF 
C0402 
5% 
50V 
NPO 
NI 
R520 
R0402 
0
5% 
NI 
R532 10K 
1% R0402 
NI 
C367 
0.1UF 
X7R 
16V 
10% 
C0402 
NI 



5
5
4
4
3
3
2
2
1
1
D D
C C
B B
A A
Title 
Size Document Number Rev
Date: Sheet 
of 
Blank 1A
Chassis Manager Assembly V1 
Cloud Server Infrastructure Engineering
C
48 85Monday, January 27, 2014 
Title 
Size Document Number Rev
Date: Sheet 
of 
Blank 1A
Chassis Manager Assembly V1 
Cloud Server Infrastructure Engineering
C
48 85Monday, January 27, 2014 
Title 
Size Document Number Rev
Date: Sheet 
of 
Blank 1A
Chassis Manager Assembly V1 
Cloud Server Infrastructure Engineering
C
48 85Monday, January 27, 2014 



5
5
4
4
3
3
2
2
1
1
D D
C C
B B
A A
PLACE 0.1UF CAPACITORS CLOSE TO PNP DEVICE PINS 
PLACE PNP 0.5 INCH FROM THE 82574L 
PLACE SUFFICIENT COPPER UNDER PNP FOR THERMAL RELIEF 
PLACE THE 4 CAPACITORS AT 4 CENTER TAP PIN SEPARATELY 
CAD NOTE: 0.1U CAPACITOR CLOSE TO EACH PIN 
THAT USE P3V3 
CAD NOTE: 0.1U CAPACITOR CLOSE TO EACH PIN 
THAT USE P1V9_LAN1 
CLOSE TO PIN 19 
CAD NOTE: 0.1U CAPACITOR CLOSE TO EACH PIN 
THAT USE P1V05_LAN1 
PLT_RST_LAN1_N 
LAN1_TEST_EN 
LAN1_AUX_PWR 
PU_LAN1_TMS 
PU_LAN1_TDI 
SMB_LAN1_ALT_N 
SMB_LAN1_DAT 
SMB_LAN1_CLK 
SPI_LAN1_NVM_SI 
SPI_LAN1_NVM_SO 
SPI_LAN1_NVM_SK 
SPI_LAN1_NVM_CS_N 
LAN1_RST 
LAN1_LED_LINK_100_N 
LAN1_LED_ACT_N 
LAN1_LED_LINK_1000_N 
LAN1_CTRL_P1V9 
LAN1_DIS_REG10 
LAN1_NC_SI_CRS_DV 
LAN1_NC_SI_TX_EN 
LAN1_NC_SI_CLK_IN 
LAN1_DIS_REG10 
LAN1_NC_SI_RXD1 
LAN1_NC_SI_RXD0 
LAN1_NC_SI_TDX1 
LAN1_NC_SI_TDX0 
SPI_LAN1_NVM_CS_N 
LAN1_AUX_PWR 
SMB_LAN1_DAT 
SMB_LAN1_CLK 
SMB_LAN1_ALT_N 
PU_LAN1_TDI 
PCIE_LAN1_RX_C_DP 
PCIE_LAN1_RX_C_DN 
PCIE_LAN1_RX_C_DP 
PCIE_LAN1_RX_C_DN 
PLT_RST_LAN1_N 
LAN1_TEST_EN 
SMB_LAN1_CLK 
SMB_LAN1_ALT_N 
SMB_LAN1_DAT 
LAN1_RST 
LAN1_XTAL_IN 
LAN1_XTAL_OUT 
LAN1_NC_SI_CLK_IN 
LAN1_NC_SI_TX_EN 
LAN1_NC_SI_TDX0 
LAN1_NC_SI_TDX1 
LAN1_NC_SI_CRS_DV 
LAN1_NC_SI_RXD0 
LAN1_NC_SI_RXD1 
PU_LAN1_TMS 
LAN1_DIS_REG10 
LAN1_XTAL_IN LAN1_XTAL_OUT 
LAN1_NVM_SK_R 
LAN1_NVM_SI_R 
LAN1_NVM_SO_R 
LAN1_NVM_CS_N_R 
LAN1_NVM_HOLD_N 
SPI_LAN1_NVM_CS_N 
LAN1_NVM_SO_R 
LAN1_NVM_SK_R 
LAN1_NVM_CS_N_R 
SPI_LAN1_NVM_SI 
SPI_LAN1_NVM_SO 
SPI_LAN1_NVM_SK 
LAN1_NVM_SI_R 
LAN1_NVM_WP_N 
LAN1_NVM_WP_N 
LAN1_NVM_HOLD_N 
LAN1_CTRL_P1V9_R 
LAN1_CTRL_P1V9 
LAN1_DISABLE_N 
LAN1_LED_LINK_1000_N 
LAN1_LED_LINK_100_N 
LAN1_LED_ACT_N 
LAN1_MDI0_DP (55) 
LAN1_MDI0_DN (55) 
LAN1_MDI1_DP (55) 
LAN1_MDI1_DN (55) 
LAN1_MDI2_DP (55) 
LAN1_MDI2_DN (55) 
LAN1_MDI3_DP (55) 
LAN1_MDI3_DN (55) 
CLK_100M_NIC1_NODE1_DP (13) 
CLK_100M_NIC1_NODE1_DN (13) 
P2E_CPU_NIC1_NODE1_RX_DN (15) 
P2E_CPU_NIC1_NODE1_RX_DP (15) 
P2E_CPU_NIC1_NODE1_TX_DP (15) 
P2E_CPU_NIC1_NODE1_TX_DN (15) 
IRQ_LVC3_CPU_NODE1_WAKE_L (19,30,67) 
FM_CPLD_NODE1_CPU_RESET_L (67) 
LAN1_DISABLE_N 
SMB_PCH_SDA (50) 
SMB_PCH_SCL 
PCH_I2C_ALERT_N 
P1V9_LAN1 
P1V05_LAN1 
P3V3_NODE1 
P3V3_NODE1 
P3V3_NODE1 P3V3_NODE1 
P3V3_NODE1 
P3V3_NODE1 
P1V9_LAN1 
P1V9_LAN1 
P3V3_NODE1 
P1V9_LAN1 
P1V9_LAN1 
P1V05_LAN1 
Title 
Size Document Number Rev
Date: Sheet 
of 
Node1 82574 LAN 1 1A
Chassis Manager Assembly V1 
Cloud Server Infrastructure Engineering
C
49 85Monday, January 27, 2014 
Title 
Size Document Number Rev
Date: Sheet 
of 
Node1 82574 LAN 1 1A
Chassis Manager Assembly V1 
Cloud Server Infrastructure Engineering
C
49 85Monday, January 27, 2014 
Title 
Size Document Number Rev
Date: Sheet 
of 
Node1 82574 LAN 1 1A
Chassis Manager Assembly V1 
Cloud Server Infrastructure Engineering
C
49 85Monday, January 27, 2014 
C401 
0.1UF 
R557 10K 
R0402 1% 
C392 0.1UF 
16V C0402 
C433 
0.1UF 
R555 10K 
R0402 1% 
C418 
0.1UF 
R558 1.02K 
R0402 1% 
C411 
0.1UF 
C430 
10UF 
R596 1K 
R0402 1% 
R538 4.7K 
R0402 5% 
C431 
10UF 
R543 0
R0402 5% 
TP2 1
C394 
0.1UF 
C407 
0.1UF 
C517 
470PF 
C425 
0.01UF 
C422 
0.1UF 
R536 4.7K 
R0402 5% 
C393 
10UF 
R556 10K 
R0402 1% 
C404 
0.1UF 
C432 
0.1UF 
C518 
470PF 
C429 
0.01UF 
C420 
0.1UF 
U36 
M95320-WMN6TP 
CS 1
SCK 6
SI 5
SO 2
Vcc 8
HOLD 7
WP 3
Vss 4
TP1 1
Q15 
BCP69-16 
1
3 2
4
C397 
0.1UF 
C409 
0.1UF 
intel 82574L 
U35 
WG82574L S LBA9 A1 
TEST_EN 29 
DEV_OFF 28 
AUX_PWR/JTAG_TCK 39 
NVMT/JTAG_TMS 38 
JTAG_TDI 40 
SMB_ALRT 35 
SMB_DAT 36 
SMB_CLK 34 
ATESTP 45 
ATESTN 46 
RSET 48 
NVM_SO 14 
NVM_SK 13 
NVM_SI 12 
NVM_CS 15 
VDD1p9 19 
AVDD1p9_1 63 
AVDD1p9_2 61 
AVDD1p9_3 56 
AVDD1p9_4 51 
AVDD1p9_5 47 
AVDD1p9_6 44 
AVDD1p9_7 22 
VDD1p05_1 60 
VDD1p05_2 41 
VDD1p05_3 37 
VDD1p05_4 27 
VDD1p05_5 18 
VDD1p05_6 11 
VDD1p05_7 4
VDD3p3_1 32 
VDD3p3_2 10 
AVDD3p3/VDD3p3 1
LED0 31 
LED1 30 
LED2 33 
MDI_PLUS[0] 58 
MDI_MINUS[0] 57 
MDI_PLUS[1] 55 
MDI_MINUS[1] 54 
MDI_PLUS[2] 53 
MDI_MINUS[2] 52 
MDI_PLUS[3] 50 
MDI_MINUS[3] 49 
PE_Rp 24 
PE_Rn 23 
PE_Tp 21 
PE_Tn 20 
PE_WAKE 16 
PE_RST 17 
GND TH 
NC_SI_CLK_IN 2
NC_SI_TX_EN 7
NC_SI_TXD0 9
NC_SI_TXD1 8
NC_SI_CRS_DV 3
NC_SI_RXD0 6
NC_SI_RXD1 5
XTAL1 43 
XTAL2 42 
CTRL105 62 
CTRL19 64 
DIS_REG10 59 
PECLKp 26 
PECLKn 25 
R539 4.7K 
R0402 5% 
C519 
470PF 
C419 
0.1UF 
R545 22.1 
R0402 1% 
R554 10K 
R0402 1% 
C395 
0.1UF 
C402 
0.1UF 
R537 1K 
R0402 1% 
R559 4.99K 
R0402 1% 
C396 
0.1UF 
R544 10K 
R0402 1% 
C403 
0.1UF 
C427 
0.01UF 
C391 0.1UF 
16V C0402 
R551 1K 
R0402 1% 
NI 
C398 
0.1UF 
C405 
0.1UF 
R564 
4.99K 
R546 10K 
R0402 1% 
R541 4.7K 
R0402 5% 
R560 0
R0402 5% 
C417 
0.1UF 
C412 
0.1UF 
R562 0
R0402 5% 
NI 
C428 
0.01UF 
C390 
0.1UF 
R550 10K 
R0402 1% 
C408 
0.1UF C414 
4.7UF 
R542 4.7K 
R0402 5% 
R553 10K 
R0402 1% 
C400 
27PF 
R561 0
R0402 5% 
NI 
C415 
4.7UF 
C413 
10UF 
R548 10K 
R0402 1% 
R552 1K 
R0402 1% 
R549 0
R0402 5% 
C410 
0.1UF 
C424 
10UF 
Y4 
25MHZ 
C426 
0.01UF 
C416 
0.1UF 
C421 
0.1UF 
C406 
0.1UF 
R563 0
R0402 5% 
NI 
R565 
0
R547 0
R0402 5% 
R540 4.7K 
R0402 5% 
C399 
27PF 
C423 
0.1UF 



5
5
4
4
3
3
2
2
1
1
D D
C C
B B
A A
PLACE 0.1UF CAPACITORS CLOSE TO PNP DEVICE PINS 
PLACE PNP 0.5 INCH FROM THE 82574L 
PLACE SUFFICIENT COPPER UNDER PNP FOR THERMAL RELIEF 
PLACE THE 4 CAPACITORS AT 4 CENTER TAP PIN SEPARATELY 
CAD NOTE: 0.1U CAPACITOR CLOSE TO EACH PIN 
THAT USE P3V3 
CLOSE TO PIN 19 
CAD NOTE: 0.1U CAPACITOR CLOSE TO EACH PIN 
THAT USE P1V9_LAN2 
CAD NOTE: 0.1U CAPACITOR CLOSE TO EACH PIN 
THAT USE P1V05_LAN2 
LAN2_NC_SI_RXD1 
LAN2_CTRL_P1V9 
LAN2_TEST_EN 
LAN2_DIS_REG10 
SMB_LAN2_CLK 
LAN2_NC_SI_TDX1 
LAN2_AUX_PWR 
LAN2_TEST_EN 
SMB_LAN2_CLK 
SMB_LAN2_ALT_N 
SMB_LAN2_DAT 
LAN2_NC_SI_CLK_IN 
LAN2_AUX_PWR 
LAN2_NC_SI_RXD1 
LAN2_XTAL_OUT 
SMB_LAN2_DAT 
PU_LAN2_TMS 
LAN2_RST 
PU_LAN2_TMS 
PLT_RST_LAN2_N 
SPI_LAN2_NVM_SI 
SPI_LAN2_NVM_SO 
SPI_LAN2_NVM_SK 
LAN2_NC_SI_RXD0 
LAN2_NC_SI_CRS_DV 
SMB_LAN2_CLK 
PLT_RST_LAN2_N 
PU_LAN2_TDI 
LAN2_NC_SI_TX_EN 
SPI_LAN2_NVM_CS_N 
PCIE_LAN2_RX_C_DP 
PCIE_LAN2_RX_C_DN 
LAN2_NC_SI_TDX1 
SMB_LAN2_ALT_N 
LAN2_NC_SI_CRS_DV 
LAN2_NC_SI_TDX0 
PU_LAN2_TDI 
SMB_LAN2_ALT_N 
LAN2_NC_SI_RXD0 
PCIE_LAN2_RX_C_DP 
PCIE_LAN2_RX_C_DN 
LAN2_RST 
LAN2_NC_SI_TDX0 
LAN2_NC_SI_CLK_IN 
LAN2_DIS_REG10 
LAN2_NC_SI_TX_EN 
LAN2_XTAL_IN LAN2_XTAL_OUT 
LAN2_XTAL_IN 
SMB_LAN2_DAT 
SPI_LAN2_NVM_CS_N 
LAN2_NVM_WP_N 
LAN2_NVM_SO_R 
LAN2_NVM_HOLD_N 
LAN2_NVM_SK_R 
LAN2_NVM_WP_N 
LAN2_NVM_CS_N_R 
LAN2_NVM_HOLD_N 
LAN2_NVM_SI_R 
SPI_LAN2_NVM_CS_N 
LAN2_NVM_SO_R 
LAN2_NVM_SK_R 
LAN2_NVM_CS_N_R 
SPI_LAN2_NVM_SI 
SPI_LAN2_NVM_SO 
SPI_LAN2_NVM_SK 
LAN2_NVM_SI_R 
LAN2_CTRL_P1V9 
LAN2_CTRL_P1V9_R 
LAN2_DISABLE_N 
LAN2_DIS_REG10 
LAN2_LED_LINK_100_N 
LAN2_LED_ACT_N 
LAN2_LED_LINK_1000_N 
LAN2_LED_LINK_1000_N 
LAN2_LED_LINK_100_N 
LAN2_LED_ACT_N 
LAN2_MDI0_DP (55) 
LAN2_MDI0_DN (55) 
LAN2_MDI1_DP (55) 
LAN2_MDI1_DN (55) 
LAN2_MDI2_DP (55) 
LAN2_MDI2_DN (55) 
LAN2_MDI3_DP (55) 
LAN2_MDI3_DN (55) 
P2E_CPU_NIC2_NODE1_RX_DN (15) 
P2E_CPU_NIC2_NODE1_RX_DP (15) 
P2E_CPU_NIC2_NODE1_TX_DP (15) 
P2E_CPU_NIC2_NODE1_TX_DN (15) 
IRQ_LVC3_CPU_NODE1_WAKE_L (19,30,67) 
FM_CPLD_NODE1_CPU_RESET_L (67) 
LAN2_DISABLE_N 
SMB_PCH_SDA (49) 
SMB_PCH_SCL 
PCH_I2C_ALERT_N 
CLK_100M_NIC2_NODE1_DP (13) 
CLK_100M_NIC2_NODE1_DN (13) 
P1V9_LAN2 
P1V05_LAN2 
P3V3_NODE1 
P3V3_NODE1 
P3V3_NODE1 P3V3_NODE1 
P3V3_NODE1 
P3V3_NODE1 
P1V9_LAN2 
P1V9_LAN2 
P3V3_NODE1 
P1V9_LAN2 
P1V9_LAN2 
P1V05_LAN2 
Title 
Size Document Number Rev
Date: Sheet 
of 
Node1 82574 LAN 2 1A
Chassis Manager Assembly V1 
Cloud Server Infrastructure Engineering
C
50 85Monday, January 27, 2014 
Title 
Size Document Number Rev
Date: Sheet 
of 
Node1 82574 LAN 2 1A
Chassis Manager Assembly V1 
Cloud Server Infrastructure Engineering
C
50 85Monday, January 27, 2014 
Title 
Size Document Number Rev
Date: Sheet 
of 
Node1 82574 LAN 2 1A
Chassis Manager Assembly V1 
Cloud Server Infrastructure Engineering
C
50 85Monday, January 27, 2014 
C454 
0.1UF 
C446 
4.7UF 
C461 
0.1UF 
R570 4.7K 
R0402 5% 
R583 10K 
R0402 1% 
C437 
27PF 
R582 1K 
R0402 1% 
C441 
0.1UF 
C474 
10UF 
C460 
0.1UF 
C462 
0.1UF 
R594 
4.99K 
R572 4.7K 
R0402 5% 
C439 
10UF 
C470 
0.01UF 
R567 4.7K 
R0402 5% 
R568 1K 
R0402 1% 
C463 
0.1UF 
Q16 
BCP69-16 
1
3 2
4
C444 
0.1UF 
C529 
470PF 
R586 10K 
R0402 1% 
C464 
0.1UF 
R576 10K 
R0402 1% 
R590 0
R0402 5% 
R585 10K 
R0402 1% 
C528 
470PF 
C443 
0.1UF 
R581 1K 
R0402 1% 
NI 
R578 10K 
R0402 1% 
C435 0.1UF 
16V C0402 
C452 
0.1UF 
C442 
0.1UF 
C527 
470PF 
R573 0
R0402 5% 
C471 
0.01UF 
R597 1K 
R0402 1% 
C448 
0.1UF 
C453 
0.1UF 
R587 10K 
R0402 1% 
C457 
0.1UF 
C440 
0.1UF 
R591 0
R0402 5% 
NI 
R575 22.1 
R0402 1% 
R571 4.7K 
R0402 5% 
C468 
0.01UF 
C458 
0.1UF 
C451 
0.1UF 
R592 0
R0402 5% 
NI 
C472 
0.01UF 
C438 
27PF 
R577 0
R0402 5% 
R580 10K 
R0402 1% 
C456 
0.1UF 
R584 10K 
R0402 1% 
C475 
0.1UF 
TP3 1
C459 
0.1UF 
R579 0
R0402 5% 
C469 
0.01UF 
R566 4.7K 
R0402 5% 
R595 
0
R569 4.7K 
R0402 5% 
TP4 1
C455 
0.1UF 
C465 
0.1UF 
C473 
10UF 
C447 
4.7UF 
C449 
0.1UF 
C436 0.1UF 
16V C0402 
R588 1.02K 
R0402 1% 
C466 
0.1UF 
U38 
M95320-WMN6TP 
CS 1
SCK 6
SI 5
SO 2
Vcc 8
HOLD 7
WP 3
Vss 4
intel 82574L 
U37 
WG82574L S LBA9 A1 
TEST_EN 29 
DEV_OFF 28 
AUX_PWR/JTAG_TCK 39 
NVMT/JTAG_TMS 38 
JTAG_TDI 40 
SMB_ALRT 35 
SMB_DAT 36 
SMB_CLK 34 
ATESTP 45 
ATESTN 46 
RSET 48 
NVM_SO 14 
NVM_SK 13 
NVM_SI 12 
NVM_CS 15 
VDD1p9 19 
AVDD1p9_1 63 
AVDD1p9_2 61 
AVDD1p9_3 56 
AVDD1p9_4 51 
AVDD1p9_5 47 
AVDD1p9_6 44 
AVDD1p9_7 22 
VDD1p05_1 60 
VDD1p05_2 41 
VDD1p05_3 37 
VDD1p05_4 27 
VDD1p05_5 18 
VDD1p05_6 11 
VDD1p05_7 4
VDD3p3_1 32 
VDD3p3_2 10 
AVDD3p3/VDD3p3 1
LED0 31 
LED1 30 
LED2 33 
MDI_PLUS[0] 58 
MDI_MINUS[0] 57 
MDI_PLUS[1] 55 
MDI_MINUS[1] 54 
MDI_PLUS[2] 53 
MDI_MINUS[2] 52 
MDI_PLUS[3] 50 
MDI_MINUS[3] 49 
PE_Rp 24 
PE_Rn 23 
PE_Tp 21 
PE_Tn 20 
PE_WAKE 16 
PE_RST 17 
GND TH 
NC_SI_CLK_IN 2
NC_SI_TX_EN 7
NC_SI_TXD0 9
NC_SI_TXD1 8
NC_SI_CRS_DV 3
NC_SI_RXD0 6
NC_SI_RXD1 5
XTAL1 43 
XTAL2 42 
CTRL105 62 
CTRL19 64 
DIS_REG10 59 
PECLKp 26 
PECLKn 25 
C445 
10UF 
C450 
0.1UF 
C476 
0.1UF 
C467 
0.1UF 
Y5 
25MHZ 
R593 0
R0402 5% 
NI 
R589 4.99K 
R0402 1% 
C434 
0.1UF 
R574 10K 
R0402 1% 



5
5
4
4
3
3
2
2
1
1
D D
C C
B B
A A
Title 
Size Document Number Rev
Date: Sheet 
of 
Blank 1A
Chassis Manager Assembly V1 
Cloud Server Infrastructure Engineering
C
51 85Monday, January 27, 2014 
Title 
Size Document Number Rev
Date: Sheet 
of 
Blank 1A
Chassis Manager Assembly V1 
Cloud Server Infrastructure Engineering
C
51 85Monday, January 27, 2014 
Title 
Size Document Number Rev
Date: Sheet 
of 
Blank 1A
Chassis Manager Assembly V1 
Cloud Server Infrastructure Engineering
C
51 85Monday, January 27, 2014 



5
5
4
4
3
3
2
2
1
1
D D
C C
B B
A A
P/N change to CH6222M9A02 
Note: 
*close to IT8783 
*Recommended net "SIO_VCCH" minimum trace width 12mils. 
GNDA 
Vf=0.36V 
P/N change to BF648000503 
7*5mm Size 
GPIO POET 4 BIT0~BIT3 
JP1 
JP3 
JP2 
JP4 
JP5 
JP6 
JP7 
JP8 JP9 
STRAPPING 
FROM CLOCK GEN 
CLOSE TO SIO 
SIO_VREF 
SIO_COPEN_N 
SIO_VCCH 
SIO_AVCC 
SIO_CLKIN 
SIO_VREF 
SIO_AVCC 
SIO_VCCH 
SIO_COPEN_N 
SIO_VBAT 
SIO_PCICLK33 
SIO_CLKIN 
SIO_LRESET_N 
SIO_PWROK2 
SIO_PWROK2 
SIO_PCICLK33 
SIO_LRESET_N 
OSC1_48MHZ UART_RTS_P6_N 
CPLD_WDT3_R 
SIO_GPIO47 
UART_DTR_P1_N 
UART_TX_P1 
UART_RTS_P1_N 
UART_DTR_P2_N 
UART_RTS_P2_N 
UART_TX_P2 
UART_DTR_P3_R_N 
UART_TX_P3_R UART_RTS_P3_R_N 
UART_CTS_P5_N 
SIO_PIN38 
SIO_PIN38 
SIO_PIN45 
SIO_PIN45 
UART_DSR_P6_N 
SIO_PIN72 
SIO_PIN72 
SIO_PIN73 
SIO_PIN73 
SIO_PIN75 
SIO_PIN76 
SIO_PIN76 
SIO_PIN75 
SIO_PIN78 
SIO_PIN78 
SIO_PIN80 
SIO_PIN81 
SIO_PIN82 
SIO_PIN83 
SIO_PIN80 
SIO_PIN81 
SIO_PIN82 
SIO_PIN83 
UART_RTS_P6_N 
SIO_GPIO47 
SIO_CPLD_RSV1_R 
SIO_CPLD_RSV2_R 
SIO_CPLD_RSV3_R 
CPLD_WDT3_R 
UART_RI_P2_N 
UART_RI_P1_N 
UART_RI_P2_N 
UART_RI_P1_N 
SIO_JTAG_CPLD2_TCK_R 
SIO_JTAG_CPLD2_TMS_R 
SIO_JTAG_CPLD2_TDI_R 
CPLD_WDT3_R 
SIO_CPLD_RSV1_R 
SIO_CPLD_RSV2_R 
SIO_CPLD_RSV3_R 
SIO_JTAG_CPLD2_TDO 
SIO_JTAG_CPLD3_TCK_R 
SIO_JTAG_CPLD3_TMS_R 
SIO_JTAG_CPLD3_TDI_R 
SIO_JTAG_CPLD3_TDO 
IRQ_CPU_NODE1_SERIAL_SIO 
LPC_CPU_NODE1_FRAME_SIO_L 
LPC_CPU_NODE1_LAD0_SIO 
LPC_CPU_NODE1_LAD1_SIO 
LPC_CPU_NODE1_LAD2_SIO 
LPC_CPU_NODE1_LAD3_SIO 
LPC_CPU_NODE1_FRAME_SIO_L 
LPC_CPU_NODE1_LAD1_SIO 
LPC_CPU_NODE1_LAD3_SIO 
LPC_CPU_NODE1_LAD0_SIO 
LPC_CPU_NODE1_LAD2_SIO 
IRQ_CPU_NODE1_SERIAL_SIO 
UART_RI_P5_N 
UART_RI_P6_N 
SIO_CPLD_RSV2_R 
SIO_CPLD_RSV3_R 
SIO_CPLD_RSV1_R 
SIO_JTAG_CPLD1_TCK_R 
SIO_JTAG_CPLD1_TMS_R 
SIO_JTAG_CPLD1_TDI_R 
SIO_JTAG_CPLD1_TDO 
UART_DSR_P3_N 
UART_CTS_P3_N 
UART_RI_P3_N 
UART_DCD_P3_N 
UART_RI_P4_R_N 
UART_DSR_P3_N 
UART_CTS_P3_N 
UART_DCD_P3_N 
UART_DCD_P4_N 
UART_DSR_P4_N 
UART_CTS_P4_N 
UART_DCD_P4_N 
UART_DSR_P4_N 
UART_CTS_P4_N 
UART_DTR_P2_N (56) 
UART_RTS_P2_N (56) 
UART_TX_P2 (56) 
UART_RX_P2 (56) 
UART_DSR_P2_N (56) 
UART_DTR_P3_R_N (53) 
UART_RTS_P3_R_N (53) 
UART_TX_P3_R (53) 
UART_RX_P3 (60) 
UART_DTR_P4_R_N (53) 
UART_TX_P4_R (53) 
UART_RTS_P4_R_N (53) 
UART_CTS_P2_N 
UART_RX_P1 
UART_TX_P1 (56) 
UART_DSR_P1_N 
UART_RTS_P1_N (56) 
UART_DTR_P1_N (56) 
UART_CTS_P1_N 
LPC_CPU_NODE1_CLKOUT1 (16) 
FM_CPLD_NODE1_CPU_RESET_L (67) 
UART_RX_P4_BUF 
CPLD_WDT3 (60) 
CPLD123_RSV1 (60,67) 
CPLD123_RSV2 (60,67) 
CPLD123_RSV3 (60,67) 
UART_RI_P3_N 
UART_RI_P4_R_N 
SIO_JTAG_CPLD2_TCK_R (53) 
SIO_JTAG_CPLD2_TDO 
SIO_JTAG_CPLD2_TMS_R (53) 
SIO_JTAG_CPLD2_TDI_R (53) 
CLK_48M_SIO (13) 
SIO_JTAG_CPLD3_TCK_R (53) 
SIO_JTAG_CPLD3_TMS_R (53) 
SIO_JTAG_CPLD3_TDI_R (53) 
SIO_JTAG_CPLD3_TDO (60) 
IRQ_CPU_NODE1_SERIAL (16,23) 
LPC_CPU_NODE1_FRAME_L (16) 
LPC_CPU_NODE1_LAD1 (16,23) 
LPC_CPU_NODE1_LAD2 (16,23) 
LPC_CPU_NODE1_LAD3 (16,23) 
LPC_CPU_NODE1_LAD0 (16,23) 
UART_TX_P5 (56) 
UART_RI_P5_N 
UART_RX_P5 (56) 
UART_DTR_P5_N (56) 
UART_RTS_P5_N (56) 
UART_CTS_P5_N (56) 
UART_TX_P6 (56) 
UART_RI_P6_N 
UART_RTS_P6_N (56) 
UART_RX_P6 
UART_DTR_P6_N (56) 
UART_DSR_P5_N (56) 
UART_CTS_P6_N 
UART_DSR_P6_N 
SIO_JTAG_CPLD1_TMS_R (53) 
SIO_JTAG_CPLD1_TDI_R (53) 
SIO_JTAG_CPLD1_TCK_R (53) 
SIO_JTAG_CPLD1_TDO (67) 
AA
P5V_NODE1 
A
P5V_STB_NODE1
SIO_VBAT 
SIO_VBAT P3V3_RTC_NODE1 
P5V_NODE1 
P5V_NODE1 
A
A
P3V3_NODE1 
P3V3_NODE1 
P3V3_NODE1 
P5V_NODE1 
P5V_NODE1 
P5V_NODE1 
P5V_NODE1 
P5V_NODE1 
P5V_NODE1 
P5V_NODE1 
P5V_NODE1 P5V_NODE1 
P3V3_STB_NODE1 P3V3_NODE1
P5V_NODE1 
Title 
Size Document Number Rev
Date: Sheet 
of 
SIO IT8783 1A
Chassis Manager Assembly V1 
Cloud Server Infrastructure Engineering
C
52 85Monday, January 27, 2014 
Title 
Size Document Number Rev
Date: Sheet 
of 
SIO IT8783 1A
Chassis Manager Assembly V1 
Cloud Server Infrastructure Engineering
C
52 85Monday, January 27, 2014 
Title 
Size Document Number Rev
Date: Sheet 
of 
SIO IT8783 1A
Chassis Manager Assembly V1 
Cloud Server Infrastructure Engineering
C
52 85Monday, January 27, 2014 
R1133 10K 
R0402 1% 
NI 
R1137 10K 
R0402 1% 
NI 
C482 
0.1UF 
16V 
C0402 
R1148 10K 
R0402 1% 
R1186 1.5K 
1% R0402 
NI 
R621 0
R0402 5% 
R182 33 R0402 1% 
D6 RB551V-30TE-17 
1 2
R1145 10K 
R0402 1% 
R1262 10K 
R0402 1% 
R1290 10K 
R0402 1% R616 10K 
R0402 1% 
R1139 10K 
R0402 1% 
R1013 10K 
R0402 1% 
NI 
R1138 10K 
R0402 1% 
R615 10K 
R0402 1% 
R1078 10K 
R0402 1% 
R1150 10K 
R0402 1% 
R777 10K 
R0402 1% 
R1291 1.2K 
R0402 1% 
C485
1UF
6.3V
C0402
R1149 10K 
R0402 1% 
L20 
220/2000MA 
21
R624
1K
1%
R0402
R626 10K 
R0402 1% 
R1193 10K 
R0402 1% 
R1183 1K 
1% R0402 
NI 
R815 0 NI 
R816 1.2K 
R0402 1% R814 10K 
R0402 1% 
R1056 10K 
R0402 1% 
R183 33 R0402 1% 
R1194 10K 
R0402 1% 
R1181 1K 
1% R0402 
NI 
R1140 10K 
R0402 1% 
R1184 1.5K 
1% R0402 
NI 
C487 
0.1UF 
16V 
C0402 
R1322 10K 
R0402 1% 
R1005 10K 
R0402 1% 
OSC4 
OSC 48MHz 
BF648000601 
OE 1 GND 2
OUT 3VDD 4
R1201 10K 
R0402 1% 
R1141 10K 
R0402 1% 
R1008 10K 
R0402 1% 
NI 
R1020 10K 
R0402 1% 
R1182 1.5K 
1% R0402 
NI 
R95 33 R0402 1% 
C488 
22UF 
10V 
*LF_C0805 
R1134 1K 
R0402 1% 
R1263 10K 
R0402 1% 
R1146 10K 
R0402 1% 
R1195 10K 
R0402 1% 
C484 
0.1UF 
16V 
C0402 
R614 10K 
R0402 1% 
R1323 10K 
R0402 1% 
R1142 10K 
R0402 1% 
R1202 10K 
R0402 1% 
L36 
BLM15BB221SN1D 
300MA 
L0402 
21
R625 0
R0402 5% 
R184 33 R0402 1% 
R1017 10K 
R0402 1% 
R1077 10K 
R0402 1% 
R1143 10K 
R0402 1% 
R1024 10K 
R0402 1% 
NI 
R628 10_4 
R1009 10K 
R0402 1% R1179 1K 
1% R0402 
NI 
R1288 10K 
R0402 1% 
R181 33 R0402 1% 
R1135 10K 
R0402 1% 
NI 
R1147 10K 
R0402 1% 
R620 10K 
R0402 1% 
U43 
IT8783F-L 
AJ087830000 
CTS2# 128 
RI2# 127 
DCD2# 126 
SIN1 125 
SOUT1/JP3 124 
DSR1# 123 
RTS1#/JP2 122 
DTR1#/JP1 121 
CTS1# 120 
RI1# 119 
DCD1# 118 
GNDD 117 
PD7/GP67 116 
PD6/GP66 115 
PD5/GP65 114 
PD4/GP64 113 
PD3/GP63 112 
PD2/GP62 111 
PD1/GP61 110 
PD0/GP60 109 
STB#/SMBC_M 108 
AFD#/SMBC_R/(DCD6#) 107 
ERR#/(RTS6#) 106 
INIT#/SMBD_M/(SOUT6) 105 
SLIN#/SMBD_R/(SIN6) 104 
ACK#/(DTR6#) 103 
SERIRQ 39 
LFRAME# 40 
LAD0 41 
LAD1 42 
LAD2 43 
LAD3 44 
KRST#/GP36 45 
GA20 46 
PCICLK 47 
SIN5/GP23 48 
CLKIN 49 
GNDD 50 
DENSEL#/PWROK2 51 
MTRA#/GP50 52 
SST/MTRB#/PCIRST1#/PECIRQT 53 
DRVA#/GP51 54 
PECI/DRVB# 55 
WDATA#/GP52 56 
DIR#/GP53 57 
STEP#/GP54 58 
HDSEL#/GP55 59 
WGATE#/GP56 60 
RDATA#/GP57 61 
TRK0#/CIRTX 62 
INDEX#/CIRRX 63 
WPT#/IRTX 64 
BUSY/(DSR6#) 102 
PE/(CTS6#) 101 
SLCT/(RI6#) 100 
AVCC 99 
VIN0 98 
VIN1 97 
VIN2 96 
VIN3/ATXPG/DSR6# 95 
VIN4/DCD6# 94 
VIN5/FAN_TAC3/SIN6/GP30 93 
VIN6/CTS6#/GP31 92 
VIN7/SO/GP32 91 
VREF 90 
TMPIN1 89 
TMPIN2 88 
TMPIN3/RI6# 87 
GNDA(D-) 86 
RSMRST#/RTS6#/GP34/CIRRX1 85 
DCD5#/GP20 84 
MCLK/GP10 83 
MDAT/GP11 82 
KCLK/GP12 81 
KDAT/GP13 80 
3VSBSW#/GP40 79 
PWROK1/GP41 78 
SUSC#/SOUT6/GP35 77 
PSON#/GP42 76 
PANSWH#/GP43 75 
GNDD 74 
PME#/GP45 73 
PWRON#/GP46 72 
SUSB#/GP47 71 
RI5#/GP21 70 
VBAT 69 
COPEN# 68 
VCCH 67 
SOUT5/GP22 66 
DSKCHG#/IRRX 65 
DTR2#/JP4 1
RTS2#/JP5 2
DSR2# 3
VCC 4
SOUT2/JP6 5
SIN2 6
FAN_TAC1 7
FAN_CTL1 8
FAN_TAC2/GP37 9
FAN_CTL2/GP33 10 
DCD3# 11 
RI3# 12 
CTS3# 13 
DTR3#/JP7 14 
GNDD 15 
RTS3#/JP9 16 
DSR3# 17 
SOUT3#/JP8 18 
SIN3# 19 
DCD4# 20 
RI4# 21 
CTS4# 22 
DTR4# 23 
SI/GP17/PCIRST3# 24 
SCK/GP16/PCIRST2# 25 
RTS4# 26 
DSR4# 27 
SOUT4 28 
DTR6#/GP15 29 
CE_N/FAN_CTL3/GP14 30 
SIN4 31 
RESETCON#/CTS5#/GP27 32 
DTR5#/GP26 33 
RTS5#/GP25 34 
VCC 35 
DSR5#/GP24 36 
LRESET# 37 
LDRQ# 38 
R1136 1K 
R0402 1% 
R1132 1K 
R0402 1% 
C483 
10UF 
10V 
C0603 
R1203 10K 
R0402 1% 
R1180 1.5K 
1% R0402 
NI 
R1325 10K 
R0402 1% 
C481 
0.1UF 
16V 
10% 
C0402 
R1015 10K 
R0402 1% 
R618 0
R617 10K 
R0402 1% 
C536 
0.1UF 
16V 
10% 
C0402 
R1289 10K 
R0402 1% 
R1264 10K 
R0402 1% 
R1018 10K 
R0402 1% 
NI 
C486 
1UF 
10V 
C0402 
R1011 10K 
R0402 1% 
R1065 10K 
R0402 1% 
R1185 1K 
1% R0402 
NI 
R1204 1.2K 
R0402 1% 
R619 1K 
1% R0402 
R1144 10K 
R0402 1% 
R1010 10K 
R0402 1% 
NI 
L37 
BLM15BB221SN1D 
L0402 21
R185 33 R0402 1% 
R776 10K 
R0402 1% 
R1016 10K 
R0402 1% 
NI 



5
5
4
4
3
3
2
2
1
1
D D
C C
B B
A A
UART_TX_P4_BUF 
COM4_EN_N 
COM4_EN_N 
COM4_EN_N 
UART_RX_P4 
UART_TX_P4_BUF 
UART_DTR_P3_N UART_DTR_P3_R_N (52) 
UART_RTS_P3_N (60) UART_RTS_P3_R_N (52) 
UART_TX_P3 UART_TX_P3_R (52) 
UART_TX_P4_R (52) 
UART_DTR_P4_N UART_DTR_P4_R_N (52) 
UART_RTS_P4_N UART_RTS_P4_R_N (52) 
CPLD_UART_RX_P3 (60) CPLD_UART_RX_P3_R (56) 
CPLD_UART_RTS_P3_N (60) CPLD_UART_RTS_P3_R_N 
CPLD_UART_DTR_P3_N (60) CPLD_UART_DTR_P3_R_N 
CPLD_UART_RX_P4 (60) CPLD_UART_RX_P4_R (56) 
CPLD_UART_RTS_P4_N (60) CPLD_UART_RTS_P4_R_N 
CPLD_UART_DTR_P4_N (60) CPLD_UART_DTR_P4_R_N 
SIO_JTAG_CPLD2_TDI SIO_JTAG_CPLD2_TDI_R (52) 
SIO_JTAG_CPLD2_TCK SIO_JTAG_CPLD2_TCK_R (52) 
SIO_JTAG_CPLD2_TMS SIO_JTAG_CPLD2_TMS_R (52) 
SIO_JTAG_CPLD3_TDI SIO_JTAG_CPLD3_TDI_R (52) 
SIO_JTAG_CPLD3_TCK SIO_JTAG_CPLD3_TCK_R (52) 
SIO_JTAG_CPLD3_TMS SIO_JTAG_CPLD3_TMS_R (52) 
UART_TX_P4 (60)
CPLD_UART_RI_P3_N (56) 
UART_RX_P4_BUF
UART_RX_P4 (60) 
SIO_JTAG_CPLD1_TDI SIO_JTAG_CPLD1_TDI_R (52) 
SIO_JTAG_CPLD1_TCK SIO_JTAG_CPLD1_TCK_R (52) 
SIO_JTAG_CPLD1_TMS SIO_JTAG_CPLD1_TMS_R (52) 
UART_RI_P4_N (60) UART_RI_P4_R_N 
UART_RI_P3_BUFFER_N (60) UART_RI_P3_N 
P3V3_NODE1 
P3V3_NODE1 
P3V3_NODE1 
P3V3_NODE1 
P3V3_NODE1 
P3V3_NODE1 
P3V3_NODE1 
P3V3_NODE1 
P3V3_NODE1 
P3V3_NODE1 
P3V3_NODE1 
Title 
Size Document Number Rev
Date: Sheet 
of 
Divider 1A
Chassis Manager Assembly V1 
Cloud Server Infrastructure Engineering
C
53 85Monday, January 27, 2014 
Title 
Size Document Number Rev
Date: Sheet 
of 
Divider 1A
Chassis Manager Assembly V1 
Cloud Server Infrastructure Engineering
C
53 85Monday, January 27, 2014 
Title 
Size Document Number Rev
Date: Sheet 
of 
Divider 1A
Chassis Manager Assembly V1 
Cloud Server Infrastructure Engineering
C
53 85Monday, January 27, 2014 
R1329 
4.7K 
R0402 
5% 
R1171 2K 
5% R0402 
NI 
C599 
0.1UF 
16V 
10% 
C0402 
R1173 0
5% R0402 
R1164 1K 
1% R0402 
R1157 1K 
1% R0402 
R1207 0
5% R0402 
R1191 2K 
5% R0402 
NI 
C539 
0.1UF 
16V 
10% 
C0402 
R1172 2K 
5% R0402 
NI 
R1192 2K 
5% R0402 
NI 
R1174 2K 
5% R0402 
NI 
C598 
0.1UF 
16V 
10% 
C0402 
R1158 2K 
5% R0402 
R1165 2K 
5% R0402 
U103 
2N7002LT1G 
G
D S
R1167 0
5% R0402 
R1187 0
5% R0402 
R1330 
4.7K 
R0402 
5% 
R1268 0
5% R0402 
R521 0
R0402 5% 
NI 
R1324 0
5% R0402 
NI 
R1166 2K 
5% R0402 
U135 
SN74LVC1G125DCKR 
A2
B 4GND 3
OE# 1 VCC 5
R1327 0
5% R0402 
NI 
R1175 0
5% R0402 
U136 
SN74LVC1G125DCKR 
A2
B 4GND 3
OE# 1 VCC 5
R1161 1K 
1% R0402 
C538 
0.1UF 
16V 
10% 
C0402 
R1269 2K 
5% R0402 
NI 
R1168 2K 
5% R0402 
NI 
R1188 2K 
5% R0402 
NI 
R1326 2K 
5% R0402 
NI 
R1208 0
5% R0402 
R1217 
10K 
R1328 2K 
5% R0402 
NI 
R1162 2K 
5% R0402 
U145 
SN74LVC1G07DCKR 
VCC 5
A2
GND 3
Y 4
NC 1
R1270 2K 
5% R0402 
NI 
R1209 2K 
5% R0402 
NI 
R1169 0
5% R0402 
R1265 0
5% R0402 
R1159 1K 
1% R0402 
R1189 0
5% R0402 
R1176 0
5% R0402 
R1205 0
5% R0402 
R1210 2K 
5% R0402 
NI 
R1163 1K 
1% R0402 
R1160 2K 
5% R0402 
R1155 1K 
1% R0402 
R1177 2K 
5% R0402 
NI 
R1266 2K 
5% R0402 
NI 
U146 
SN74LVC1G07DCKR 
VCC 5
A2
GND 3
Y 4
NC 1
R1170 0
5% R0402 
R1206 2K 
5% R0402 
NI 
R1190 0
5% R0402 
R1178 2K 
5% R0402 
NI 
R1267 0
5% R0402 
R1156 2K 
5% R0402 



5
5
4
4
3
3
2
2
1
1
D D
C C
B B
A A
SATA DOM
CLOSE TO J7 POWER PIN 
Close to J9 
POWER CONN FOR SATA DOM 
SATA_P7 
I2C_VIDREAR_5V_SCL 
I2C_VIDREAR_5V_SDA 
CRT_DDCDATA 
CRT_DDCCLK 
CRT_VSYNC 
VCC5_CRTXX 
CRT_B 
CRT_G 
CRT_HSYNC 
CRT_R 
I2C_VIDREAR_5V_SDA 
I2C_VIDREAR_5V_SCL 
VGA_VSYNC 
VGA_HSYNC 
CRT_B 
CRT_G 
CRT_R 
CRT_DDCDATA 
CRT_HSYNC 
CRT_DDCCLK 
CRT_VSYNC 
SATA_P7 
SATA_RX0_C_DN 
SATA_RX0_C_DP 
SATA_TX0_C_DN 
SATA_TX0_C_DP 
SATA_RX0_C_DN 
SATA_RX0_C_DP 
SATA_TX0_C_DN 
SATA_TX0_C_DP 
SATA_P7 
GFX_BUF_EN_N 
GFX_BUF_EN_N 
GFX_BUF_EN_N 
VGA_VSYNC VGA_HSYNC 
CRT_B_L 
CRT_G_L 
CRT_R_L 
SMB_BMC_NODE1_DDC_DAT (35) 
SATA_A_NODE1_TX_P0 (45) 
SATA_A_NODE1_TX_N0 (45) 
SMB_BMC_NODE1_DDC_CLK (35) 
SATA_A_NODE1_RX_P0 
SATA_A_NODE1_RX_N0 
BMC_NODE1_GFX_VSYNC (35) 
BMC_NODE1_GFX_HSYNC 
BMC_NODE1_GFX_RED (35) 
BMC_NODE1_GFX_BLUE (35) 
BMC_NODE1_GFX_GREEN (35) 
P5V_NODE1 
P5V_CRT 
P3V3_NODE1 
P5V_CRT 
P5V_CRT 
P5V_NODE1 
P5V_NODE1 
P3V3_NODE1 P5V_NODE1 
P5V_NODE1 
Title 
Size Document Number Rev
Date: Sheet 
of 
SATA HDD / VGA 1A
Chassis Manager Assembly V1 
Cloud Server Infrastructure Engineering
C
54 85Monday, January 27, 2014 
Title 
Size Document Number Rev
Date: Sheet 
of 
SATA HDD / VGA 1A
Chassis Manager Assembly V1 
Cloud Server Infrastructure Engineering
C
54 85Monday, January 27, 2014 
Title 
Size Document Number Rev
Date: Sheet 
of 
SATA HDD / VGA 1A
Chassis Manager Assembly V1 
Cloud Server Infrastructure Engineering
C
54 85Monday, January 27, 2014 
L41 
BLM18BB750SN1D 200MA 
NI 21
C508 100PF 
NI 
C494 0.01UF 
16V C0402 
R631 
4.7K 
5% 
R0402 
NI 
L39 
BLM18BB750SN1D 200MA 
NI 21
Q17 
FDV301N 
NI 
G
DS
C507 100PF 
NI 
L40 
BLM18BB750SN1D 200MA 
NI 21
U48 BAT54S-7-F 
NI 
2 1
3
C493 
0.1UF 
16V 
C0402 
C491 
1UF 
16V 
C0603 
Q18 
FDV301N 
NI 
G
DS
R659 33 
R0402 
NI 
R633 
4.7K 
5% 
R0402 
NI 
R630 0
R0805 
C503 3.3PF 
50V NPO 
C0603 
NI 
D7 
BAT54LT1G 
NI 
1 3
R632 
4.7K 
5% 
R0402 
NI 
R788 33 
R0402 
NI 
C498 
0.1UF 16V 
C0402 
X7R NI 
R639 33 
R0402 
NI 
U45 BAT54S-7-F 
NI 
2 1
3
U50 BAT54S-7-F 
NI 
2 1
3
U47 BAT54S-7-F 
NI 
2 1
3
R634 
4.7K 
5% 
R0402 
NI 
J9 
CONN15_15DZ11A51H8R14F 
NI 
8
15 
7
14 
6
13 
5
12 
4
11 
3
10 
2
9
1
G1 
G2 
C492 0.01UF 
16V C0402 
C497 
0.1UF C0402 
16V 
X7R NI 
R640 150 
1% R0402 
NI 
U132 
74HC2G125DP 
NI 
1OE_N 1
A1 2
Y2 3
GND 4 A2 5
Y1 6
2OE_N 7
Vcc 8
CD1 
1SS355 
NI 
1 2
C496 
1UF 
16V 
C0603 
<Not_insert> 
C506 100PF 
NI 
R635 
4.7K 
5% 
R0402 
NI 
R641 150 
1% R0402 
NI 
C504 3.3PF 
50V NPO 
C0603 
NI 
D8 
BAT54LT1G 
NI 
1 3
C505 100PF 
NI 
J7 
ABA-SAT-054-T02 
CONN DIP HEADER 7P 1R MS(P1.055,H8.9) 
11
33
44
55
22
66
77
G1 8
G2 9
R637 33 
R0402 
NI 
R642 150 
1% R0402 
NI 
C535 
0.1UF 
16V 
C0402 
NI 
R629 0
R0805 
NI 
U49 BAT54S-7-F 
NI 
2 1
3
C499 3.3PF 
50V NPO 
C0603 
NI 
L38 
BLM18PG300S 
1A 
NI 
2 1
J8 
CONN2_ASP13867601 
12
C509 0.1UF 
NI 
C501 3.3PF 
50V NPO 
C0603 
NI 
C502 3.3PF 
50V NPO 
C0603 
NI 
R636 0
R0402 
NI 
R638 33 
R0402 
NI 
FS2 1.1A/6V NI 
12
C489 0.01UF 
16V C0402 
C495 
0.1UF 
16V 
C0402 
  
R658 0
R0402 
NI 
C500 3.3PF 
50V NPO 
C0603 
NI 
C490 0.01UF 
16V C0402 
R789 33 
R0402 
NI 
U46 BAT54S-7-F 
NI 
2 1
3
U44 BAT54S-7-F 
NI 
2 1
3



5
5
4
4
3
3
2
2
1
1
D D
C C
B B
A A
check pin define 
LAN1_P1_R 
LAN1_P2_R 
LAN1_P3_R 
LAN1_P4_R 
LAN1_P4_R 
LAN1_P2_R 
LAN1_P1_R 
LAN1_P3_R 
LAN2_P4_R 
LAN2_P2_R 
LAN2_P1_R 
LAN2_P4_R 
LAN2_P2_R 
LAN2_P1_R 
LAN2_P3_R 
LAN2_P3_R 
LAN1_P1_P (61) 
LAN1_P1_N (61) 
LAN1_P2_P (61) 
LAN1_P2_N (61) 
LAN1_P3_P (61) 
LAN1_P3_N (61) 
LAN1_P4_P (61) 
LAN1_P4_N (61) 
LAN2_P2_P (61) 
LAN2_P2_N (61) 
LAN2_P3_P (61) 
LAN2_P3_N (61) 
LAN2_P4_P (61) 
LAN2_P4_N (61) 
LAN2_P1_P (61) 
LAN2_P1_N (61) 
LAN1_MDI0_DP (49) 
LAN1_MDI0_DN (49) 
LAN1_MDI1_DP (49) 
LAN1_MDI1_DN (49) 
LAN1_MDI2_DP (49) 
LAN1_MDI2_DN (49) 
LAN1_MDI3_DP (49) 
LAN1_MDI3_DN (49) 
LAN2_MDI0_DP (50) 
LAN2_MDI0_DN (50) 
LAN2_MDI1_DP (50) 
LAN2_MDI1_DN (50) 
LAN2_MDI2_DP (50) 
LAN2_MDI2_DN (50) 
LAN2_MDI3_DP (50) 
LAN2_MDI3_DN (50) 
P1V9_LAN1 
P1V9_LAN1 
P1V9_LAN2 
P1V9_LAN2 
Title 
Size Document Number Rev
Date: Sheet 
of 
LAN Transformer 1A
Chassis Manager Assembly V1 
Cloud Server Infrastructure Engineering
C
55 85Monday, January 27, 2014 
Title 
Size Document Number Rev
Date: Sheet 
of 
LAN Transformer 1A
Chassis Manager Assembly V1 
Cloud Server Infrastructure Engineering
C
55 85Monday, January 27, 2014 
Title 
Size Document Number Rev
Date: Sheet 
of 
LAN Transformer 1A
Chassis Manager Assembly V1 
Cloud Server Infrastructure Engineering
C
55 85Monday, January 27, 2014 
C524 
0.1UF 
U137 
NA0069R LF 
TRD1_P 1
TRD1_N 2 TRD1 3
TRD2_P 5
TRD2 4
TRD2_N 6
TRD3_P 7
TRD3 9
TRD3_N 8
TRD4_P 11 
TRD4 10 
TRD4_N 12 
P1_P 24 
P1 22 
P1_N 23 
P2_P 20 
P2 21 
P2_N 19 
P3_P 18 
P3 16 
P3_N 17 
P4_P 14 
P4 15 
P4_N 13 
C511 
0.1UF 
C523 
0.1UF 
U138 
NA0069R LF 
TRD1_P 1
TRD1_N 2 TRD1 3
TRD2_P 5
TRD2 4
TRD2_N 6
TRD3_P 7
TRD3 9
TRD3_N 8
TRD4_P 11 
TRD4 10 
TRD4_N 12 
P1_P 24 
P1 22 
P1_N 23 
P2_P 20 
P2 21 
P2_N 19 
P3_P 18 
P3 16 
P3_N 17 
P4_P 14 
P4 15 
P4_N 13 
R1273 75 
C512 
0.1UF 
C520 
1UF 
R1274 75 
R1275 75 
C513 
0.1UF 
C540 
1000PF 
2000V 
R1277 75 
C522 
0.1UF 
R1278 75 
R1276 75 
C541 
1000PF 
2000V 
R1279 75 
C514 
0.1UF 
C510 
1UF 
C521 
0.1UF 
R1280 75 



5
5
4
4
3
3
2
2
1
1
D D
C C
B B
A A
FROM SIO (MASTER) FROM SIO (MASTER) 
FROM SIO (MASTER) 
TO CPLD(SALVE) TO CPLD(SALVE) 
UART_RI_P5_LS_N UART_RI_P6_LS_N 
CPLD_UART_RI_P3_LS_N CPLD_UART_RI_P4_LS_N 
TACKOVER_EN 
TACKOVER_EN 
TACKOVER_EN TACKOVER_EN 
TACKOVER_EN 
CPLD_UART_RI_P3_LS_N 
CPLD_UART_RI_P4_LS_N 
UART_RI_P5_LS_N 
UART_RI_P6_LS_N 
UART_RI_P5_LS_N 
UART_RI_P6_LS_N 
UART_TX_P1 (52) 
UART_RTS_P1_N (52) 
UART_DTR_P1_N (52) 
UART_DSR_P1_N 
UART_CTS_P1_N 
UART_RX_P1 
UART_DSR_P2_N (52) 
UART_CTS_P2_N 
UART_RX_P2 (52) 
UART_TX_P2 (52) 
UART_RTS_P2_N (52) 
UART_DTR_P2_N (52) 
UART_TX_P5 (52) 
UART_RTS_P5_N (52) 
UART_DTR_P5_N (52) 
UART_RX_P5 (52) 
UART_TX_P6 (52) 
UART_RTS_P6_N (52) 
UART_DTR_P6_N (52) 
UART_RX_P6 
CPLD_UART_TX_P3 
CPLD_UART_RTS_P3_R_N 
CPLD_UART_DTR_P3_R_N 
CPLD_UART_RX_P3_R (53) 
CPLD_UART_TX_P4 
CPLD_UART_RTS_P4_R_N 
CPLD_UART_DTR_P4_R_N 
CPLD_UART_RX_P4_R (53) 
UART_RTS_P1_L_N 
UART_TX_P1_L 
UART_DTR_P1_L_N (61) 
UART_RX_P1_L 
UART_DSR_P1_L_N 
UART_CTS_P1_L_N (61) 
UART_DTR_P2_L_N (61) 
UART_RX_P2_L 
UART_DSR_P2_L_N 
UART_CTS_P2_L_N (61) 
UART_RTS_P2_L_N 
UART_TX_P2_L 
UART_DTR_P5_L_N (61) 
UART_RX_P5_L 
UART_RI_P5_L_N (61) 
UART_RTS_P5_L_N 
UART_TX_P5_L 
UART_DTR_RP5_L_N (61) 
UART_RX_RP5_L 
UART_RI_RP5_L_N (61) 
UART_RTS_RP5_L_N 
UART_TX_RP5_L 
UART_DTR_RP6_L_N (61) 
UART_RX_RP6_L (61) 
UART_RI_RP6_L_N (61) 
UART_RTS_RP6_L_N (61) 
UART_TX_RP6_L (61) 
UART_DSR_P5_L_N 
UART_CTS_P5_L_N UART_CTS_P6_L_N (61) 
UART_DSR_P6_L_N (61) 
UART_DTR_P6_L_N (61) 
UART_RX_P6_L 
UART_RI_P6_L_N (61) 
UART_RTS_P6_L_N 
UART_TX_P6_L 
UART_CTS_P5_N (52) 
UART_DSR_P5_N (52) 
UART_CTS_P6_N 
UART_DSR_P6_N 
TACKOVER_EN_N (60) 
CPLD_UART_RI_P3_N (53,60) 
CPLD_UART_RI_P4_N (60) UART_RI_P6_N 
UART_RI_P5_N 
P3V3_NODE1 
P3V3_NODE1 
P3V3_NODE1 
P3V3_NODE1 
P3V3_NODE1 
P3V3_NODE1 
P3V3_NODE1 
P3V3_NODE1 
P3V3_NODE1 
P3V3_NODE1 
P3V3_NODE1 
P3V3_NODE1 
P3V3_NODE1 
P3V3_NODE1 
Title 
Size Document Number Rev
Date: Sheet 
of 
RS232 Driver/Receiver 1A
Chassis Manager Assembly V1 
Cloud Server Infrastructure Engineering
C
56 85Monday, January 27, 2014 
Title 
Size Document Number Rev
Date: Sheet 
of 
RS232 Driver/Receiver 1A
Chassis Manager Assembly V1 
Cloud Server Infrastructure Engineering
C
56 85Monday, January 27, 2014 
Title 
Size Document Number Rev
Date: Sheet 
of 
RS232 Driver/Receiver 1A
Chassis Manager Assembly V1 
Cloud Server Infrastructure Engineering
C
56 85Monday, January 27, 2014 
C554 0.1UF 
R1068 0
R0402 5% 
NI 
U142 2N7002LT1G 
G
DS
R1299 4.7K 
C543 
0.1UF 
U57 
MAX3243CPWR 
FORCEON 23 
C1- 24 
VCC 26 
C1+ 28 
FORCEOFF# 22 
ROUT2B 20 
DIN1 14 
DIN2 13 
DIN3 12 
ROUT1 19 
ROUT2 18 
ROUT3 17 
ROUT4 16 
ROUT5 15 
C2+ 1
GND 25 
C2- 2
V+ 27 
V- 3
INVALID# 21 
DOUT1 9
DOUT2 10 
DOUT3 11 
RIN1 4
RIN2 5
RIN3 6
RIN4 7
RIN5 8
R1306 
1K 
R654 
1K 
C530 
0.1UF 
C913 
0.1UF 
R656 
1K 
U59 
MAX3243CPWR 
FORCEON 23 
C1- 24 
VCC 26 
C1+ 28 
FORCEOFF# 22 
ROUT2B 20 
DIN1 14 
DIN2 13 
DIN3 12 
ROUT1 19 
ROUT2 18 
ROUT3 17 
ROUT4 16 
ROUT5 15 
C2+ 1
GND 25 
C2- 2
V+ 27 
V- 3
INVALID# 21 
DOUT1 9
DOUT2 10 
DOUT3 11 
RIN1 4
RIN2 5
RIN3 6
RIN4 7
RIN5 8
R1300 
1K 
R1304 4.7K 
R1311 10K 
R1307 4.7K 
R650 4.7K 
C542 0.1UF 
R1305 4.7K 
R1310 10K 
C918 
0.1UF 
R1309 4.7K 
U56 
MAX3243CPWR 
FORCEON 23 
C1- 24 
VCC 26 
C1+ 28 
FORCEOFF# 22 
ROUT2B 20 
DIN1 14 
DIN2 13 
DIN3 12 
ROUT1 19 
ROUT2 18 
ROUT3 17 
ROUT4 16 
ROUT5 15 
C2+ 1
GND 25 
C2- 2
V+ 27 
V- 3
INVALID# 21 
DOUT1 9
DOUT2 10 
DOUT3 11 
RIN1 4
RIN2 5
RIN3 6
RIN4 7
RIN5 8
C551 0.1UF 
R649 4.7K 
U143 2N7002LT1G 
G
DS
C548 0.1UF 
U52 
MAX3243CPWR 
FORCEON 23 
C1- 24 
VCC 26 
C1+ 28 
FORCEOFF# 22 
ROUT2B 20 
DIN1 14 
DIN2 13 
DIN3 12 
ROUT1 19 
ROUT2 18 
ROUT3 17 
ROUT4 16 
ROUT5 15 
C2+ 1
GND 25 
C2- 2
V+ 27 
V- 3
INVALID# 21 
DOUT1 9
DOUT2 10 
DOUT3 11 
RIN1 4
RIN2 5
RIN3 6
RIN4 7
RIN5 8
C555 
0.1UF 
C549 0.1UF 
R652 4.7K 
R1297 
1K 
R1301 4.7K 
R1308 4.7K 
U144 2N7002LT1G 
G
DS
C544 0.1UF 
R1302 4.7K 
C563 0.1UF 
R1069 0
R0402 5% 
NI 
R1061 0
R0402 5% 
NI 
C914 0.1UF 
U141 2N7002LT1G 
G
DS
R651 4.7K 
C564 0.1UF 
C915 0.1UF 
C545 0.1UF 
R1064 0
R0402 5% 
NI 
U51 
MAX3243CPWR 
FORCEON 23 
C1- 24 
VCC 26 
C1+ 28 
FORCEOFF# 22 
ROUT2B 20 
DIN1 14 
DIN2 13 
DIN3 12 
ROUT1 19 
ROUT2 18 
ROUT3 17 
ROUT4 16 
ROUT5 15 
C2+ 1
GND 25 
C2- 2
V+ 27 
V- 3
INVALID# 21 
DOUT1 9
DOUT2 10 
DOUT3 11 
RIN1 4
RIN2 5
RIN3 6
RIN4 7
RIN5 8
C912 0.1UF 
C534 0.1UF 
C916 0.1UF 
C547 0.1UF 
U55 
MAX3243CPWR 
FORCEON 23 
C1- 24 
VCC 26 
C1+ 28 
FORCEOFF# 22 
ROUT2B 20 
DIN1 14 
DIN2 13 
DIN3 12 
ROUT1 19 
ROUT2 18 
ROUT3 17 
ROUT4 16 
ROUT5 15 
C2+ 1
GND 25 
C2- 2
V+ 27 
V- 3
INVALID# 21 
DOUT1 9
DOUT2 10 
DOUT3 11 
RIN1 4
RIN2 5
RIN3 6
RIN4 7
RIN5 8
C533 0.1UF 
C917 0.1UF 
C552 0.1UF 
C531 0.1UF 
C919 0.1UF 
C546 0.1UF 
C550 
0.1UF 
C562 0.1UF 
R1303 
1K 
U140 
2N7002LT1G 
G
D S
C553 0.1UF 
C532 0.1UF 
R1298 4.7K 



5
5
4
4
3
3
2
2
1
1
D D
C C
B B
A A
60mil 
Current limit =1.5~2A 
60mil 
60mil 60mil 
USB0_L_DP 
USBPWR_P1 
USB2_L_DN 
USB2_L_DP 
USBPWR_P1 
USBPWR_P1 
USB3_L_DN 
USB3_L_DP 
USB2_L_DP 
USB2_L_DN 
USB3_L_DP 
USB3_L_DN 
USB0_L_DN 
USB0_L_DP 
USBPWR_P0 
USB0_L_DN 
USBPWR_P0 
USB1_L_DP 
USBPWR_P0 
USB1_L_DN 
USB1_L_DP 
USBPWR_P1 
USBPWR_P0 
USB1_L_DN 
USB0_L_DP 
USB0_L_DN 
USB2_L_DP 
USB2_L_DN 
USB3_L_DP 
USB3_L_DN 
USB1_L_DP 
USB1_L_DN 
USB0_DN (47) 
USB0_DP (47) 
USB1_DP (47) 
USB1_DN (47) 
USB3_DP (47) 
USB3_DN (47) 
USB2_DP (47) 
USB2_DN (47) 
P5V_NODE1 
P5V_NODE1 
Title 
Size Document Number Rev
Date: Sheet 
of 
USB & Header 1A
Chassis Manager Assembly V1 
Cloud Server Infrastructure Engineering
C
57 85Monday, January 27, 2014 
Title 
Size Document Number Rev
Date: Sheet 
of 
USB & Header 1A
Chassis Manager Assembly V1 
Cloud Server Infrastructure Engineering
C
57 85Monday, January 27, 2014 
Title 
Size Document Number Rev
Date: Sheet 
of 
USB & Header 1A
Chassis Manager Assembly V1 
Cloud Server Infrastructure Engineering
C
57 85Monday, January 27, 2014 
R269 0
5% R0402 
NI 
C557 
470PF 
50V 
NI 
R270 0
5% R0402 
NI 
FS4 
1.5A/8V 
NI 
1 2
R266 0
5% R0402 
NI 
L45 
90/400MA 
NI 
4 3
21
L42 
90/400MA 
NI 
4 3
21
R271 0
5% R0402 
NI 
D10 
UCLAMP0501T 
NI 
A
C
D9 
UCLAMP0501T 
NI 
A
C
R267 0
5% R0402 
NI 
+ CE3 
220UF 
6.3V 
NI 
1 2
R265 0
5% R0402 
NI 
L43 
90/400MA 
NI 
4 3
21
C561 
470PF 
50V 
NI 
+ CE2 
220UF 
6.3V 
NI 
1 2
1 2 3 4
5 6 7 8
J14 
USBX2 
NI 
1
2
3
4
5
6
7
8
9
10 
11 
12 
C556 
4.7UF 
10V 
NI 
FS3 
1.5A/8V 
NI 
1 2
U53 
IP4220CZ6 
NI 
ESD_P1 1
ESD_P2 3 ESD_P3 4ESD_P4 6
VP 5
GND 2
C560 
470PF 
50V 
NI 
L44 
90/400MA 
NI 
4 3
21
C559 
4.7UF 
10V 
NI 
1 2 3 4
5 6 7 8
J15 
USBX2 
NI 
1
2
3
4
5
6
7
8
9
10 
11 
12 
R268 0
5% R0402 
NI 
U54 
IP4220CZ6 
NI 
ESD_P1 1
ESD_P2 3 ESD_P3 4ESD_P4 6
VP 5
GND 2
R264 0
5% R0402 
NI 
C558 
470PF 
50V 
NI 



5
5
4
4
3
3
2
2
1
1
D D
C C
B B
A A
ADDRESS 0X40h 
ADDRESS 0X42h 
ADDRESS 0X48h 
ENABLE HAVE INTERNAL PULL-UP RESISTORS 
ADDRESS 0XA0h 
ADDRESS 0X44h 
internal pull-up 
ADDRESS 0X4Ah 
To have the device leave the power-down state 
WAKEUP pin should be brought LOW. 
RESERVE 
VF=2.5 
VF=2.5 
FROM CPLD 
PSU2_HUB_EN 
I2C_COM3_SCL 
PSU3_HUB_EN 
I2C_COM3_SDA 
I2C_COM3_SCL 
I2C_COM3_SDA 
I2C_COM3_SCL 
I2C_COM3_SDA 
I2C_PSU1_SCL_MOS 
PU_I2C_SCL4 
I2C_PSU1_SDA_MOS 
PU_I2C_SDA4 
UART3_RESET_N 
I2C_PSU2_SCL_MOS 
I2C_PSU2_SDA_MOS 
PCA9535_INT_N 
I2C_PSU3_SCL_MOS 
I2C_PSU3_SDA_MOS 
I2C_COM3_SDA 
I2C_COM3_SCL 
PU_I2C_SCL4 
PU_I2C_SDA4 
PCA9535_INT_N 
I2C_COM3_SDA 
I2C_COM3_SCL 
PSU1_HUB_EN 
PSU2_HUB_EN 
PSU3_HUB_EN 
PCA9535_INT_N 
I2C_COM3_SDA 
I2C_COM3_SCL 
I2C_COM3_SDA 
I2C_COM3_SCL 
I2C_COM3_SDA 
I2C_COM3_SCL 
PSU1_HUB_EN 
COM3_WAKEUP 
COM3_WAKEUP 
CPLD_WDT1_R 
CPLD_WDT1_R 
I2C_COM3_SDA_RC 
PSU1_HUB_EN 
PSU2_HUB_EN 
PSU3_HUB_EN 
UART_CMC_RX_P 
T9_NODE1_EN 
T9_NODE2_EN 
T9_NODE3_EN 
T9_NODE4_EN 
T6_NODE1_EN 
T6_NODE2_EN 
T6_NODE3_EN 
T6_NODE4_EN 
T11_NODE1_EN 
T11_NODE2_EN 
T11_NODE3_EN 
T11_NODE4_EN 
T1_NODE1_EN 
T3_NODE1_EN 
T3_NODE2_EN 
T3_NODE3_EN 
T3_NODE4_EN 
T8_NODE1_EN 
T8_NODE2_EN 
T8_NODE3_EN 
T8_NODE4_EN 
T5_NODE1_EN 
T5_NODE2_EN 
T5_NODE3_EN 
T5_NODE4_EN 
T2_NODE1_EN 
T2_NODE2_EN 
T2_NODE3_EN 
T2_NODE4_EN 
T10_NODE1_EN 
T10_NODE2_EN 
T10_NODE3_EN 
T10_NODE4_EN 
T12_NODE1_EN 
T12_NODE2_EN 
T12_NODE3_EN 
T12_NODE4_EN 
T7_NODE1_EN 
T7_NODE2_EN 
T7_NODE3_EN 
T7_NODE4_EN 
T1_NODE2_EN 
T4_NODE1_EN 
T4_NODE2_EN 
T4_NODE3_EN 
T4_NODE4_EN 
T1_NODE3_EN 
T1_NODE4_EN 
CM_STATUS_LED_R 
LED_PWR_GD 
ATTENTION_LED_R 
CM_STATUS_LED_R ATTENTION_LED_N 
CM_STATUS_LED_N ATTENTION_LED_R 
CM_STATUS_LED_N 
ATTENTION_LED_N 
PMBUS1_EN 
PMBUS2_EN 
PMBUS3_EN 
PMBUS1_EN 
I2C_PSU1_SCL_MOS 
I2C_PSU1_SDA_MOS 
PMBUS1_EN 
I2C_PSU2_SDA_MOS 
PMBUS2_EN 
I2C_PSU2_SCL_MOS 
PMBUS2_EN 
I2C_PSU3_SDA_MOS 
PMBUS3_EN 
I2C_PSU3_SCL_MOS 
PMBUS3_EN 
I2C_PSU1_SDA_MOS 
I2C_PSU1_SCL_MOS 
I2C_PSU2_SDA_MOS 
I2C_PSU2_SCL_MOS 
I2C_PSU3_SDA_MOS 
I2C_PSU3_SCL_MOS 
ATTENTION_LED_N 
CM_STATUS_LED_N 
UART_CMC_RX_P (60) 
UART_CMC_TX_P (60) 
PSU2_AC_OK (62) 
PSU2_DC_OK (62) 
PSU4_DC_OK (62) 
PSU3_DC_OK (62) 
PSU6_DC_OK (62) 
PSU5_DC_OK (62) 
PSU1_DC_OK (62) 
PSU4_AC_OK (62) 
PSU3_AC_OK (62) 
PSU6_AC_OK (62) 
PSU5_AC_OK (62) 
T11_NODE1_EN 
T11_NODE2_EN 
T11_NODE3_EN 
T11_NODE4_EN 
T12_NODE1_EN 
T12_NODE2_EN 
T12_NODE3_EN 
T12_NODE4_EN 
T9_NODE1_EN 
T9_NODE2_EN 
T9_NODE3_EN 
T9_NODE4_EN 
T10_NODE1_EN 
T10_NODE2_EN 
T10_NODE3_EN 
T10_NODE4_EN 
T7_NODE1_EN 
T7_NODE2_EN 
T7_NODE3_EN 
T7_NODE4_EN 
T8_NODE1_EN 
T8_NODE2_EN 
T8_NODE3_EN 
T8_NODE4_EN 
T5_NODE1_EN 
T5_NODE2_EN 
T5_NODE3_EN 
T5_NODE4_EN 
T6_NODE1_EN 
T6_NODE2_EN 
T6_NODE3_EN 
T6_NODE4_EN 
T3_NODE1_EN 
T3_NODE2_EN 
T3_NODE3_EN 
T3_NODE4_EN 
T4_NODE1_EN 
T4_NODE2_EN 
T4_NODE3_EN 
T4_NODE4_EN 
T1_NODE1_EN 
T1_NODE2_EN 
T1_NODE3_EN 
T1_NODE4_EN 
T2_NODE1_EN 
T2_NODE2_EN 
T2_NODE3_EN 
T2_NODE4_EN 
PSU1_AC_OK (62) 
PSU_ALERT_N 
FAN_MAX_CTRL (60) 
CPLD_WDT1 (60) 
CMC_CPU_RST_N (60) 
CMC_CPLD_RSV1 
UART3_RESET_N (60) 
I2C_PDB_SDA (62)
I2C_COM3_SCL (59) I2C_PDB_SCL 
I2C_COM3_SDA (59) 
I2C_COM3_SCL 
I2C_COM3_SDA (59) 
LED_PWR_NODE1_L (67) 
I2C_PSU1_SCL (62) 
I2C_PSU1_SDA (62) 
I2C_PSU2_SDA (62) 
I2C_PSU2_SCL (62) 
I2C_PSU3_SDA (62) 
I2C_PSU3_SCL (62) 
CM_STATUS_LED_N (67) 
POWER_SW1_PWR_CTR_N 
POWER_SW2_PWR_CTR_N 
TACKOVER_EN_N (60) 
POWER_SW3_PWR_CTR_N 
PCA_CPLD_WDT2 (60) 
CPLD_THRMTRIP_LOG_N 
P3V3_NODE1 
P3V3_NODE1 
P3V3_NODE1 
P3V3_NODE1 
P3V3_NODE1 
P3V3_NODE1 
P3V3_NODE1 
P3V3_NODE1 
P3V3_NODE1 
P3V3_NODE1 
P3V3_NODE1 
P3V3_NODE1 
P3V3_NODE1 
P3V3_NODE1 
P3V3_NODE1 
P3V3_NODE1 
P3V3_NODE1 
P3V3_NODE1 
P3V3_NODE1 
P3V3_NODE1 
P3V3_NODE1 
P3V3_NODE1 
P3V3_NODE1 
P3V3_NODE1 
P5V_NODE1
P3V3_NODE1 
P3V3_NODE1 
P3V3_NODE1 
P5V_NODE1
Title 
Size Document Number Rev
Date: Sheet 
of 
CMC 1A
Chassis Manager Assembly V1 
Cloud Server Infrastructure Engineering
C
58 85Monday, January 27, 2014 
Title 
Size Document Number Rev
Date: Sheet 
of 
CMC 1A
Chassis Manager Assembly V1 
Cloud Server Infrastructure Engineering
C
58 85Monday, January 27, 2014 
Title 
Size Document Number Rev
Date: Sheet 
of 
CMC 1A
Chassis Manager Assembly V1 
Cloud Server Infrastructure Engineering
C
58 85Monday, January 27, 2014 
R648 0
R0402 5% 
NI 
R718 
100 
R690 10K NI 
R721 10K NI 
R708 4.7K 
PCA9516APW 
U60 
SCL0 1
SDA0 2
SCL1 3
SDA1 4
EN1 5
SCL2 6
SDA2 7
GND 8EN2 9
SCL3 10 
SDA3 11 
EN3 12 
SCL4 13 
SDA4 14 
EN4 15 
VCC 16 
R714 10K NI 
R694 10K NI 
R697 10K NI 
R712 10K NI 
R668 4.7K 
R666 4.7K 
C571 
0.1UF 
16V 
C0402 
X7R 
R710 10K NI 
R727 10K NI 
R695 10K NI 
R753 
100 
R739 
4.7K 
NI 
R724 10K NI 
R686 4.7K 
C566 
0.1UF 
16V 
C0402 
X7R 
R688 
100 
R673 4.7K NI 
R735 
4.7K 
  
R696 10K NI 
R681 0
R0402 5% 
NI 
R743 4.7K 
R645 0
R0402 5% 
NI 
U61 
SC18IM700IPW 
GPIO0 1
GPIO1 2
RESET 3
VSS 4
GPIO2 5
GPIO3 6
SDA 7
SCL 8
GPIO7 16 
GPIO4 15 
GPIO5 14 
WAKEUP 13 
VDD 12 
GPIO6 11 
TX 10 
RX 9
R1243 10K NI 
U62 
PCA9535CPW 
VDD 24 
VSS 12 
INT 1
SDA 23 
SCL 22 
P0_0 4
P0_1 5
P0_2 6
P0_3 7
P0_4 8
P0_5 9
P0_6 10 
P0_7 11 
P1_0 13 
P1_1 14 
P1_2 15 
P1_3 16 
P1_4 17 
P1_5 18 
P1_6 19 
P1_7 20 
A0 21 
A1 2
A2 3
R749 10K NI 
R711 10K NI 
R740 10K NI 
G
R
D18 
LED RED/GREEN 
3
2
1
R703 10K NI 
R744 10K NI 
R698 10K NI 
R738 
4.7K 
NI 
R669 10K 
R667 10K 
R728 10K NI 
R687 
100 
R643 0
R0402 5% 
NI 
R813 100 
R0402 1% 
R746 10K NI 
R723 10K NI 
R674 10K 
C776 
0.1UF 
X7R 
16V 
R732 10K NI 
R754 
100 
R663 2.7K 
C569 
0.1UF 
16V 
C0402 
X7R 
R725 10K NI 
R683 0
R0402 5% 
NI 
R689 10K NI 
R699 10K NI 
R706 4.7K 
U65 
PCA9535CPW 
VDD 24 
VSS 12 
INT 1
SDA 23 
SCL 22 
P0_0 4
P0_1 5
P0_2 6
P0_3 7
P0_4 8
P0_5 9
P0_6 10 
P0_7 11 
P1_0 13 
P1_1 14 
P1_2 15 
P1_3 16 
P1_4 17 
P1_5 18 
P1_6 19 
P1_7 20 
A0 21 
A1 2
A2 3
R677 10K 
R808 100
R0402 1% 
R705 10K NI 
R704 4.7K 
R736 10K NI 
R623 0
R0402 5% 
C573 
0.1UF 
16V 
C0402 
X7R 
C572 
0.1UF 
16V 
C0402 
X7R 
R745 10K NI 
R644 0
R0402 5% 
NI 
R1244 10K NI 
R700 10K NI 
R1284 4.7K 
R0402 5% 
R692 10K NI 
R647 0
R0402 5% 
NI 
R672 10K 
R1282 4.7K 
R0402 5% 
U131 
74LVC2G14GW 
1A 1
GND 2
2A 3
2Y 4
VCC 5
1Y 6
U66 
PCA9535CPW 
VDD 24 
VSS 12 
INT 1
SDA 23 
SCL 22 
P0_0 4
P0_1 5
P0_2 6
P0_3 7
P0_4 8
P0_5 9
P0_6 10 
P0_7 11 
P1_0 13 
P1_1 14 
P1_2 15 
P1_3 16 
P1_4 17 
P1_5 18 
P1_6 19 
P1_7 20 
A0 21 
A1 2
A2 3
R707 10K NI 
R1248 4.7K 
R0402 5%   
R817 100 
R0402 1% 
U64 
PCA9535CPW 
VDD 24 
VSS 12 
INT 1
SDA 23 
SCL 22 
P0_0 4
P0_1 5
P0_2 6
P0_3 7
P0_4 8
P0_5 9
P0_6 10 
P0_7 11 
P1_0 13 
P1_1 14 
P1_2 15 
P1_3 16 
P1_4 17 
P1_5 18 
P1_6 19 
P1_7 20 
A0 21 
A1 2
A2 3
C590 
33PF 
16V 
C0402 
NP0 
R702 4.7K 
R737 
4.7K 
NI 
R716 10K NI 
R691 10K NI 
R726 10K NI 
R146 1K 
1% R0402 
R671 4.7K 
R715 10K NI 
R750 
100 
R717 10K NI 
U127 
FDV301N 
G
D S
R709 10K NI 
U116 
FDV301N 
G
D S
R665 10K 
R1283 4.7K 
R0402 5% 
G
R
D19 
LED RED/GREEN 
3
2
1
C567 
0.1UF 
16V 
C0402 
X7R 
R742 10K NI 
R795 75 
R752 
100 
U139 
FDV301N 
G
D S
R685 4.7K 
R722 10K NI 
R646 0
R0402 5% 
NI 
R730 10K NI 
R729 10K NI 
R720 10K NI 
R682 100 
R713 10K NI 
U118 
FDV301N 
G
D S
R1245 10K NI 
R751 
100 
R145 1K 
1% R0402 
R680 10K NI 
R733 10K NI 
U126 
FDV301N 
G
D S
R693 10K NI 
R748 10K NI 
R734 4.7K 
U117 
FDV301N 
G
D S
R747 10K NI 
R741 10K NI 
R701 4.7K 
R731 10K NI 
C568 
0.1UF 
16V 
C0402 
X7R 
C570 
0.1UF 
16V 
C0402 
X7R 
R719 
100 
U63 
PCA9535CPW 
VDD 24 
VSS 12 
INT 1
SDA 23 
SCL 22 
P0_0 4
P0_1 5
P0_2 6
P0_3 7
P0_4 8
P0_5 9
P0_6 10 
P0_7 11 
P1_0 13 
P1_1 14 
P1_2 15 
P1_3 16 
P1_4 17 
P1_5 18 
P1_6 19 
P1_7 20 
A0 21 
A1 2
A2 3
R792 100 
R0402 1% 
R664 2.7K 
U67 
M24C64 
VCC 8
WP 7
SCL 6
SDA 5 GND 4A2 3A1 2A0 1



5
5
4
4
3
3
2
2
1
1
D D
C C
B B
A A
ADDRESS:0X58 
Reserve 
Reserve 
ADDRESS:0X5E 
OD TYPE 
FNACTRL2_TMP_IN 
TMP05_FUNC2 
FNACTRL2_T_ST 
FNACTRL1_TMP_IN 
I2C_ALERT_FNACTRL1_N 
I2C_SCL_FANCTRL2_R 
I2C_SDA_FANCTRL2_R 
FAN2_TACH_IN 
FNACTRL1_TMP_IN 
FAN3_TACH_IN 
TMP05_FUNC1 
FAN4_TACH_IN 
I2C_ALERT_FNACTRL2_N 
TMP05_FUNC2 
I2C_SCL_FANCTRL1_R 
TMP05_FUNC1 
I2C_SCL_FANCTRL2_R 
I2C_SDA_FANCTRL2_R 
I2C_SDA_FANCTRL1_R 
CPLD_FAN_MAX_CTRL 
FAN6_TACH_IN 
FAN5_TACH_IN 
FNACTRL2_T_ST 
FNACTRL2_TMP_IN 
FNACTRL2_ADD 
I2C_ALERT_FNACTRL2_N 
FAN1_TACH_IN 
FNACTRL2_ADD 
FNACTRL1_ADD 
I2C_SCL_FANCTRL1_R 
I2C_SDA_FANCTRL1_R 
FNACTRL1_ADD 
I2C_ALERT_FNACTRL1_N 
FAN_PWM_BUF 
FAN_PWM_BUF 
PU_FAN_TACH 
PU_FAN_TACH 
FAN_PWM_BUF 
FAN1_TACH 
FAN2_TACH 
FAN3_TACH 
FAN4_TACH 
FAN6_TACH 
FAN5_TACH 
I2C_COM3_SDA (58) 
I2C_COM3_SCL (58) 
I2C_COM3_SCL (58) 
I2C_COM3_SDA (58) 
FAN_PWM (62) 
CPLD_FAN_MAX_CTRL (60) 
P3V3_NODE1 
P3V3_NODE1 
P3V3_NODE1 
P3V3_NODE1 
P3V3_NODE1 
P3V3_NODE1
P3V3_NODE1
P3V3_NODE1 
P3V3_NODE1 
P3V3_NODE1 
P3V3_NODE1 
P3V3_NODE1 
P3V3_NODE1 
Title 
Size Document Number Rev
Date: Sheet 
of 
ADT7470 1A
Chassis Manager Assembly V1 
Cloud Server Infrastructure Engineering
C
59 85Monday, January 27, 2014 
Title 
Size Document Number Rev
Date: Sheet 
of 
ADT7470 1A
Chassis Manager Assembly V1 
Cloud Server Infrastructure Engineering
C
59 85Monday, January 27, 2014 
Title 
Size Document Number Rev
Date: Sheet 
of 
ADT7470 1A
Chassis Manager Assembly V1 
Cloud Server Infrastructure Engineering
C
59 85Monday, January 27, 2014 
R769 
10K 
C576 
0.1UF 
X5R 
25V 
NI 
C575 
0.1UF 
X7R 
16V 
R766 
4.7K 
R762 
10K 
R761 100 
R759 
4.7K 
C577 
0.1UF 
X7R 
16V 
R758 100 
R767
4.7K
C766 
0.1UF 
X7R 
16V 
R773 0
R771 
10K 
NI 
U68 
TMP05ARTZ-500RL7 
NI 
OUT 1
CONV/IN 2
FUNC 3 GND 4
VDD 5
R774 0
U70 
ADT7470ARQZ 
SCL 1
SDA 16 TACH1 6
TACH2 7
TACH3 4
TACH4 9
PWM1 15 
PWM2 5
PWM3 8
VCC 3
GND 2
ADDR 11 TMP_IN 12 FLSPD/T_ST 13 SALT 14 
PWM4 10 
U133 
SN74LVC1G07DCKR 
VCC 5
A 2
GND 3
Y4
NC 1
R756 100 
R768 100 
R778 
10K 
NI 
U71 
TMP05ARTZ-500RL7 
NI 
OUT 1
CONV/IN 2
FUNC 3 GND 4
VDD 5
R764 0
R770 100 
R760 
4.7K 
R763 
10K 
NI 
R772 
10K 
R799 
10K 
R757 100 
C574 
0.1UF 
X5R 
25V 
NI 
U69 
ADT7470ARQZ 
SCL 1
SDA 16 TACH1 6
TACH2 7
TACH3 4
TACH4 9
PWM1 15 
PWM2 5
PWM3 8
VCC 3
GND 2
ADDR 11 TMP_IN 12 FLSPD/T_ST 13 SALT 14 
PWM4 10 
R765 0



5
5
4
4
3
3
2
2
1
1
D D
C C
B B
A A
To have the device leave the power-down state 
WAKEUP pin should be brought LOW. 
CPLD3 CPLD2 
CMC 
SDC 
SIO 
CPU 
CMC 
SDC 
SIO 
CPU 
JTAG_CPLD2_TMS 
JTAG_CPLD2_TDI 
JTAG_CPLD2_TCK 
JTAG_CPLD2_TDO 
JTAG_CPLD3_TDI 
JTAG_CPLD3_TDO 
JTAG_CPLD3_TCK 
JTAG_CPLD3_TMS 
JTAG_CPLD2_TMS 
JTAG_CPLD2_TCK 
JTAG_CPLD2_TDI 
JTAG_CPLD2_TDO 
CLK_33K_CPLD23 CLK_33K_CPLD23 
UART_SW_S4_N 
UART_SW_S1_N 
UART_SW_S5_N 
UART_SW_S2_N 
UART_SW_S3_N 
UART_SW_S0_N 
UART_SW_S0_N 
UART_SW_S1_N 
UART_SW_S2_N 
UART_SW_S3_N 
UART_SW_S4_N 
UART_SW_S5_N 
SDC_RST_N 
UART_SW_S4_N 
UART_SW_S5_N 
UART_SW_S4_N 
UART_SW_S3_N 
SDC_WAKEUP 
CLK_33K_CPLD23 
I2C_SDC_SCL 
I2C_SDC_SDA 
SDC_WAKEUP 
SDC_RST_N 
UART_SW_S1_N 
UART_SW_S5_N 
UART_SW_S2_N 
UART_SW_S1_N 
UART_SW_S0_N 
UART_SW_S2_N 
UART_SDC_TX 
CM_CABLE_DET_N 
UART_SW_S3_N 
UART_SDC_RX 
SDC_WAKEUP 
I2C_SDC_SCL 
I2C_SDC_SDA 
UART_SW_S0_N 
UART_SW_S4_N 
UART_SW_S1_N 
UART_SW_S5_N 
UART_SW_S2_N 
UART_SW_S3_N 
UART_SW_S0_N 
CPLD_WDT2 CPLD_WDT2_R 
UART_SDC_TX 
UART_SDC_RX 
CPLD_UART_DTR_P3_N 
CPLD_UART_RTS_P3_N 
CPLD_UART_RI_P3_N 
CPLD_UART_DTR_P4_N 
CPLD_UART_RTS_P4_N 
CPLD_UART_RI_P4_N 
TACKOVER_EN_N 
TACKOVER_EN_N 
TACKOVER_EN_N 
CPLD_WDT2_R 
CPLD_WDT2 CPLD_WDT2 
JTAG_CPLD2_TMS 
JTAG_CPLD2_TCK 
JTAG_CPLD2_TDI 
JTAG_CPLD2_TDO 
CPLD_WDT2_R 
CPLD2_RSV3 
CPLD2_RSV1 
CPLD2_RSV2 
CPLD3_RSV3 
CPLD3_RSV1 
CPLD3_RSV2 
CPLD2_RSV3 
CPLD2_RSV1 
CPLD2_RSV2 
CPLD3_RSV3 
CPLD3_RSV1 
CPLD3_RSV2 
WDT_LED 
WDT_LED 
PCA_CPLD_WDT2 
JTAG_CPLD3_TMS 
JTAG_CPLD3_TCK 
JTAG_CPLD3_TDI 
JTAG_CPLD3_TDO 
JTAG_CPLD3_TMS 
JTAG_CPLD3_TCK 
JTAG_CPLD3_TDI 
JTAG_CPLD3_TDO 
FAN_MAX_CTRL 
JTAG_CPLD2_TMS 
JTAG_CPLD2_TCK 
JTAG_CPLD2_TDI 
JTAG_CPLD3_TMS 
JTAG_CPLD3_TCK 
JTAG_CPLD3_TDI 
FAN_MAX_CTRL 
CPLD_UART_RI_P3_N 
CPLD_UART_RI_P4_N 
UART_DTR_P4_N 
UART_RTS_P4_N 
UART_T1_NODE1_RXD (64) 
UART_T1_NODE1_TXD (64) 
UART_T1_NODE2_RXD (64) 
UART_T1_NODE2_TXD (64) 
UART_T1_NODE3_RXD (64) 
UART_T1_NODE3_TXD (64) 
UART_T1_NODE4_RXD (64) 
UART_T1_NODE4_TXD (64) 
UART_T2_NODE1_RXD (64) 
UART_T2_NODE4_RXD (64) 
UART_T2_NODE4_TXD (64) 
UART_T2_NODE3_RXD (64) 
UART_T2_NODE3_TXD (64) 
UART_T2_NODE1_TXD (64) 
UART_T2_NODE2_RXD (64) 
UART_T2_NODE2_TXD (64) 
UART_T3_NODE1_TXD 
UART_T3_NODE1_RXD 
UART_T3_NODE2_TXD 
UART_T3_NODE2_RXD 
UART_T3_NODE3_TXD 
UART_T3_NODE3_RXD 
UART_T3_NODE4_TXD 
UART_T3_NODE4_RXD 
UART_T4_NODE4_TXD 
UART_T4_NODE4_RXD 
UART_T4_NODE1_TXD 
UART_T4_NODE3_TXD 
UART_T4_NODE3_RXD 
UART_T4_NODE1_RXD 
UART_T4_NODE2_TXD 
UART_T4_NODE2_RXD 
UART_T5_NODE1_TXD 
UART_T5_NODE1_RXD 
UART_T5_NODE4_TXD 
UART_T5_NODE4_RXD 
UART_T5_NODE3_TXD 
UART_T5_NODE3_RXD 
UART_T5_NODE2_TXD 
UART_T5_NODE2_RXD 
UART_T6_NODE1_TXD 
UART_T6_NODE1_RXD 
UART_T6_NODE4_TXD 
UART_T6_NODE4_RXD 
UART_T6_NODE3_TXD 
UART_T6_NODE3_RXD 
UART_T6_NODE2_TXD 
UART_T6_NODE2_RXD 
UART_T7_NODE1_RXD (65) 
UART_T7_NODE4_RXD (65) 
UART_T7_NODE4_TXD (65) 
UART_T7_NODE3_RXD (65) 
UART_T7_NODE3_TXD (65) 
UART_T7_NODE1_TXD (65) 
UART_T7_NODE2_RXD (65) 
UART_T7_NODE2_TXD (65) 
UART_T8_NODE1_RXD (65) 
UART_T8_NODE4_RXD (65) 
UART_T8_NODE4_TXD (65) 
UART_T8_NODE3_RXD (65) 
UART_T8_NODE3_TXD (65) 
UART_T8_NODE1_TXD (65) 
UART_T8_NODE2_RXD (65) 
UART_T8_NODE2_TXD (65) 
UART_T9_NODE4_TXD 
UART_T9_NODE4_RXD 
UART_T11_NODE1_TXD 
UART_T11_NODE1_RXD 
UART_T10_NODE4_TXD 
UART_T10_NODE4_RXD 
UART_T10_NODE1_TXD 
UART_T10_NODE3_TXD 
UART_T10_NODE3_RXD 
UART_T10_NODE1_RXD 
UART_T10_NODE2_TXD 
UART_T10_NODE2_RXD 
UART_T9_NODE1_TXD 
UART_T11_NODE4_TXD 
UART_T11_NODE4_RXD 
UART_T11_NODE3_TXD 
UART_T11_NODE3_RXD 
UART_T11_NODE2_TXD 
UART_T11_NODE2_RXD 
UART_T9_NODE3_TXD 
UART_T9_NODE3_RXD 
UART_T9_NODE1_RXD 
UART_T12_NODE1_TXD 
UART_T12_NODE1_RXD 
UART_T12_NODE4_TXD 
UART_T12_NODE4_RXD 
UART_T12_NODE3_TXD 
UART_T12_NODE3_RXD 
UART_T12_NODE2_TXD 
UART_T12_NODE2_RXD 
UART_T9_NODE2_TXD 
UART_T9_NODE2_RXD 
CPLD_WDT3 (52) 
CPU_RSV_1 (16) 
CPLD_WDT3 (52) 
CPU_RSV_1 (16) 
CPLD_EXT_RST_N (67) 
CPLD_WDT1 (58) CPLD_WDT1 (58) 
SIO_JTAG_CPLD2_TCK 
SIO_JTAG_CPLD2_TMS 
SIO_JTAG_CPLD2_TDO 
SIO_JTAG_CPLD2_TDI 
CM_CABLE_DET_N 
CPLD_UART_RX_P4 (53) 
CPLD_UART_RI_P4_N (56) 
CPLD_UART_TX_P4 
CPLD_UART_DTR_P4_N (53) 
CPLD_UART_RTS_P4_N (53) 
CPLD_UART_TX_P3 
CPLD_UART_DTR_P3_N (53) 
CPLD_UART_RX_P3 (53) 
CPLD_UART_RI_P3_N (56) 
CPLD_UART_RTS_P3_N (53) 
CPLD123_RSV1 (52,67) 
CPLD123_RSV2 (52,67) 
CPLD123_RSV3 (52,67) 
CPLD123_RSV1 (52,67) 
CPLD123_RSV2 (52,67) 
CPLD123_RSV3 (52,67) 
TACKOVER_EN_N (56,58) 
CMC_CPLD_RSV1 
CMC_CPU_RST_N (58) 
UART_RTS_P3_N (53) 
UART3_RESET_N (58) 
UART_TX_P3 
UART_RX_P3 (52) 
UART_DTR_P3_N 
UART_CMC_RX_P (58) 
UART_TX_P4 
UART_RX_P4 (53) 
UART_CMC_TX_P (58) 
UART_RI_P3_BUFFER_N (53) 
UART_RI_P4_N (53) 
FAN_MAX_CTRL (58) 
CPLD_FAN_MAX_CTRL (59) 
PCA_CPLD_WDT2 (58) 
SIO_JTAG_CPLD3_TCK 
SIO_JTAG_CPLD3_TMS 
SIO_JTAG_CPLD3_TDO (52) 
SIO_JTAG_CPLD3_TDI 
UART_TX_P4 (52,53) 
UART_RX_P4 
P3V3_NODE1 P3V3_NODE1 
P3V3_NODE1 
P3V3_NODE1 
P3V3_NODE1 
P3V3_NODE1 
P3V3_NODE1 
P3V3_NODE1 
P3V3_NODE1 
P3V3_NODE1 
P3V3_NODE1
P3V3_NODE1 
P3V3_NODE1 
Title 
Size Document Number Rev
Date: Sheet 
of 
SDC 1A
Chassis Manager Assembly V1 
Cloud Server Infrastructure Engineering
C
60 85Monday, January 27, 2014 
Title 
Size Document Number Rev
Date: Sheet 
of 
SDC 1A
Chassis Manager Assembly V1 
Cloud Server Infrastructure Engineering
C
60 85Monday, January 27, 2014 
Title 
Size Document Number Rev
Date: Sheet 
of 
SDC 1A
Chassis Manager Assembly V1 
Cloud Server Infrastructure Engineering
C
60 85Monday, January 27, 2014 
R1048 510 
R1055 33 
R0402 1% 
C907 
0.1UF 
X7R 
16V 
C583 
0.1UF 
X7R 
16V 
R1252 4.7K 
R0402 5% 
R790 4.7K 
R0402 5% 
NI 
R775 0
R0402 5% 
NI 
R1225 4.7K 
R0402 5% 
NI 
R779 4.7K 
R0402 5% 
R1213 10K 
1% R0402 
R1261 4.7K 
R0402 5% 
R1075 10K 
1% R0402 
C584 
0.1UF 
X7R 
16V 
R791 4.7K 
R0402 5% 
NI 
R806 100K 
R0402 5% 
NI 
R1079 0
R0402 5% 
R794 100K 
R0402 5% 
NI 
D17 
LED SMD GREEN 
A C
R809 100K 
R0402 5% 
NI 
R1196 4.7K 
R0402 5% 
C585 
0.1UF 
X7R 
16V 
R780 4.7K 
R0402 5% 
D16 
LED SMD GREEN 
A C
R1214 10K NI 
1% R0402 
R662 0
R0402 5% 
C908 
10UF 10V 
20% 
X5R 
C0603 
R1076 10K NI 
1% R0402 
C586 
0.1UF 
X7R 
16V 
C900 
0.1UF 
X7R 
16V 
D15 
LED SMD GREEN 
A C
R1198 0
R0402 5% 
R781 4.7K 
R0402 5% 
R676 0
R0402 5% 
NI 
J32 
HEADER 1X2 
1 2
R622 0
R0402 5% 
NI 
C901 
0.1UF 
X7R 
16V 
R755 0
R0402 5% 
R1199 0
R0402 5% 
R678 0
R0402 5% 
NI 
C902 
0.1UF 
X7R 
16V 
R1080 0
R0402 5% 
R811 100K 
R0402 5% 
NI 
J26 
HEADER2X5 
NI 
1 2
3 4
5 6
7
9
8
10 
C909 
0.1UF 
X7R 
16V 
C0402 
10% 
R1200 0
R0402 5% 
C885 
10UF 10V 
20% 
X5R 
C0603 
R784 4.7K 
R0402 5% 
NI 
C903 
0.1UF 
X7R 
16V 
C578 
0.1UF 
X7R 
16V 
U73 
SC18IM700IPW 
GPIO0 1
GPIO1 2
RESET 3
VSS 4
GPIO2 5
GPIO3 6
SDA 7
SCL 8
GPIO7 16 
GPIO4 15 
GPIO5 14 
WAKEUP 13 
VDD 12 
GPIO6 11 
TX 10 
RX 9
R1081 0
R0402 5% 
R796 510 
D22 
LED SMD GREEN 
A C
R807 100K 
R0402 5% 
NI 
R810 100K 
R0402 5% 
NI 
OSC6 
32.768KHZ 
NC/INH 1 GND 2
OUT 3VDD 4
R785 4.7K 
R0402 5% 
NI 
C580 
0.1UF 
X7R 
16V 
C904 
0.1UF 
X7R 
16V 
R798 510 
D23 
LED SMD GREEN 
A C
R782 4.7K 
R0402 5% 
NI 
R1119 0
R0402 5% 
R793 4.7K 
R0402 5% 
NI 
D24 
LED SMD GREEN 
A C
U128 
EPM240T100C5N 
IO1_B1 2
IO2_B1 3
IO3_B1 4
IO4_B1 5
IO5_B1 6
IO6_B1 7
IO7_B1 8
IO8_B1 15 
IO9_B1 16 
IO10_B1 17 
IO11_B1 18 
IO12_B1 19 
IO13_B1 20 
IO14_B1 21 
IO15_B1 26 
IO16_B1 27 
IO17_B1 28 
IO18_B1 29 
IO19_B1 30 
IO20_B1 33 
IO21_B1 34 
IO22_B1 35 
IO23_B1 36 
IO24_B1 37 
IO25_B1 38 
IO26_B1 39 
IO27_B1 40 
IO28_B1 41 
IO29_B1 42 
IO30_B1 47 
IO31_B1 48 
IO32_B1 49 
IO33_B1 50 
IO34_B1 51 
IO35_B1/DEV_OE 43 
IO36_B1/DEV_CLRN 44 
IO37_B1/GCLK0 12 
IO38_B1/GCLK1 14 
IO41_B2/GCLK2 62 
IO42_B2/GCLK3 64 
TMS 22 
TDI 23 
TCK 24 
TDO 25 
GNDINT_11 11 
GNDINT_65 65 
GNDIO_10 10 
GNDIO_32 32 
GNDIO_46 46 
GNDIO_60 60 
GNDIO_79 79 
GNDIO_93 93 
IO1_B2 52 
IO2_B2 53 
IO3_B2 54 
IO4_B2 55 
IO5_B2 56 
IO6_B2 57 
IO7_B2 58 
IO8_B2 61 
IO9_B2 66 
IO10_B2 67 
IO11_B2 68 
IO12_B2 69 
IO13_B2 70 
IO14_B2 71 
IO15_B2 72 
IO16_B2 73 
IO17_B2 74 
IO18_B2 75 
IO19_B2 76 
IO20_B2 77 
IO21_B2 78 
IO22_B2 81 
IO23_B2 82 
IO24_B2 83 
IO25_B2 84 
IO26_B2 85 
IO27_B2 86 
IO28_B2 87 
IO29_B2 88 
IO30_B2 89 
IO31_B2 90 
IO32_B2 91 
IO33_B2 92 
IO34_B2 95 
IO35_B2 96 
IO36_B2 97 
IO37_B2 98 
IO38_B2 99 
IO39_B2 100 
IO40_B2 1
VCCINT_13 13 
VCCINT_63 63 
VCCIOB1_9 9
VCCIOB1_31 31 
VCCIOB1_45 45 
VCCIOB2_59 59 
VCCIOB2_80 80 
VCCIOB2_94 94 
R783 100 
R0402 1% 
R679 0
R0402 5% 
U129 
EPM240T100C5N 
IO1_B1 2
IO2_B1 3
IO3_B1 4
IO4_B1 5
IO5_B1 6
IO6_B1 7
IO7_B1 8
IO8_B1 15 
IO9_B1 16 
IO10_B1 17 
IO11_B1 18 
IO12_B1 19 
IO13_B1 20 
IO14_B1 21 
IO15_B1 26 
IO16_B1 27 
IO17_B1 28 
IO18_B1 29 
IO19_B1 30 
IO20_B1 33 
IO21_B1 34 
IO22_B1 35 
IO23_B1 36 
IO24_B1 37 
IO25_B1 38 
IO26_B1 39 
IO27_B1 40 
IO28_B1 41 
IO29_B1 42 
IO30_B1 47 
IO31_B1 48 
IO32_B1 49 
IO33_B1 50 
IO34_B1 51 
IO35_B1/DEV_OE 43 
IO36_B1/DEV_CLRN 44 
IO37_B1/GCLK0 12 
IO38_B1/GCLK1 14 
IO41_B2/GCLK2 62 
IO42_B2/GCLK3 64 
TMS 22 
TDI 23 
TCK 24 
TDO 25 
GNDINT_11 11 
GNDINT_65 65 
GNDIO_10 10 
GNDIO_32 32 
GNDIO_46 46 
GNDIO_60 60 
GNDIO_79 79 
GNDIO_93 93 
IO1_B2 52 
IO2_B2 53 
IO3_B2 54 
IO4_B2 55 
IO5_B2 56 
IO6_B2 57 
IO7_B2 58 
IO8_B2 61 
IO9_B2 66 
IO10_B2 67 
IO11_B2 68 
IO12_B2 69 
IO13_B2 70 
IO14_B2 71 
IO15_B2 72 
IO16_B2 73 
IO17_B2 74 
IO18_B2 75 
IO19_B2 76 
IO20_B2 77 
IO21_B2 78 
IO22_B2 81 
IO23_B2 82 
IO24_B2 83 
IO25_B2 84 
IO26_B2 85 
IO27_B2 86 
IO28_B2 87 
IO29_B2 88 
IO30_B2 89 
IO31_B2 90 
IO32_B2 91 
IO33_B2 92 
IO34_B2 95 
IO35_B2 96 
IO36_B2 97 
IO37_B2 98 
IO38_B2 99 
IO39_B2 100 
IO40_B2 1
VCCINT_13 13 
VCCINT_63 63 
VCCIOB1_9 9
VCCIOB1_31 31 
VCCIOB1_45 45 
VCCIOB2_59 59 
VCCIOB2_80 80 
VCCIOB2_94 94 
C905 
0.1UF 
X7R 
16V 
R797 510 
R786 4.7K 
R0402 5% 
NI 
C581 
0.1UF 
X7R 
16V 
R1057 10K 
R0402 1% 
C579 
0.1UF 
16V 
C0402 
X7R 
R1212 1K 
1% R0402 
NI 
J27 
HEADER2X5 
NI 
1 2
3 4
5 6
7
9
8
10 
D25 
LED YELLOW 
A C
R1058 510 
R1211 4.7K 
R0402 5% 
R805 510 
R812 4.7K 
R0402 5% 
R684 0
R0402 5% 
NI 
C582 
0.1UF 
X7R 
16V 
R787 4.7K 
R0402 5% 
NI 
C906 
0.1UF 
X7R 
16V 
R1074 1K 
1% R0402 
NI 
R1197 0
R0402 5% 



5
5
4
4
3
3
2
2
1
1
D D
C C
B B
A A
PDB CM 
A1 
A1 
B114 
B114 MATE_N 
J35 
J18 
UART_DSR_RP6_L_N 
UART_CTS_RP6_L 
UART_DSR_RP5_L 
UART_CTS_RP5_L_N 
UART_RI_P5_L_N_R UART_RI_P6_L_N_R 
UART_RI_RP6_L_N_R 
UART_RI_RP5_L_N_R 
UART_RI_RP5_L_N_R 
T12_NODE1_EN_R (63) 
T12_NODE2_EN_R (63) 
T12_NODE3_EN_R (63) 
T12_NODE4_EN_R (63) 
UART_T12_NODE1_RXD_R (65) 
UART_T12_NODE1_TXD_R (65) 
UART_T12_NODE2_RXD_R (65) 
UART_T12_NODE2_TXD_R (65) 
UART_T12_NODE4_RXD_R (65) 
UART_T12_NODE4_TXD_R (65) 
UART_T12_NODE3_RXD_R (65) 
UART_T12_NODE3_TXD_R (65) 
I2C_PDB_R_SCL (62) 
I2C_PDB_R_SDA (62) 
LAN2_P4_P (55) 
LAN2_P4_N (55) 
LAN2_P1_P (55) 
LAN2_P1_N (55) 
FAN_PWM_R 
I2C_PSU3_R_SDA (62) 
I2C_PSU3_R_SCL (62) 
LAN2_P2_P (55) 
LAN2_P2_N (55) 
LAN2_P3_P (55) 
LAN2_P3_N (55) 
POWER_SW3_PWR_CTR_12V_R (70) 
POWER_SW2_PWR_CTR_12V_R (70) 
POWER_SW1_PWR_CTR_12V_R (70) 
FAN4_TACH_R (62) 
FAN5_TACH_R (62) 
FAN6_TACH_R (62) 
T11_NODE1_EN_R (63) 
T11_NODE2_EN_R (63) 
T11_NODE3_EN_R (63) 
T11_NODE4_EN_R (63) 
UART_T11_NODE1_RXD_R (65) 
UART_T11_NODE1_TXD_R (65) 
UART_T11_NODE2_RXD_R (65) 
UART_T11_NODE2_TXD_R (65) 
UART_T11_NODE3_RXD_R (65) 
UART_T11_NODE3_TXD_R (65) 
UART_T11_NODE4_RXD_R (65) 
UART_T11_NODE4_TXD_R (65) 
T9_NODE1_EN_R (63) 
T9_NODE2_EN_R (63) 
T9_NODE3_EN_R (63) 
T9_NODE4_EN_R (63) 
UART_T9_NODE1_RXD_R (65) 
UART_T9_NODE1_TXD_R (65) 
UART_T9_NODE2_RXD_R (65) 
UART_T9_NODE2_TXD_R (65) 
UART_T9_NODE3_RXD_R (65) 
UART_T9_NODE3_TXD_R (65) 
UART_T9_NODE4_RXD_R (65) 
UART_T9_NODE4_TXD_R (65) 
T7_NODE1_EN_R (63) 
T7_NODE2_EN_R (63) 
T7_NODE3_EN_R (63) 
T7_NODE4_EN_R (63) 
UART_T7_NODE1_RXD_R (65) 
UART_T7_NODE1_TXD_R (65) 
UART_T7_NODE2_RXD_R (65) 
UART_T7_NODE2_TXD_R (65) 
UART_T7_NODE3_RXD_R (65) 
UART_T7_NODE3_TXD_R (65) 
UART_T7_NODE4_RXD_R (65) 
UART_T7_NODE4_TXD_R (65) 
PSU_ALERT_R_N 
T5_NODE1_EN_R (63) 
T5_NODE2_EN_R (63) 
FAN1_TACH_R 
FAN2_TACH_R 
FAN3_TACH_R 
T10_NODE1_EN_R (63) 
T10_NODE2_EN_R (63) 
T10_NODE3_EN_R (63) 
T10_NODE4_EN_R (63) 
UART_T10_NODE2_RXD_R (65) 
UART_T10_NODE2_TXD_R (65) 
UART_T10_NODE1_RXD_R (65) 
UART_T10_NODE1_TXD_R (65) 
UART_T10_NODE4_RXD_R (65) 
UART_T10_NODE4_TXD_R (65) 
UART_T10_NODE3_RXD_R (65) 
UART_T10_NODE3_TXD_R (65) 
T8_NODE1_EN_R (63) 
T8_NODE2_EN_R (63) 
T8_NODE3_EN_R (63) 
T8_NODE4_EN_R (63) 
UART_T8_NODE2_RXD_R (65) 
UART_T8_NODE2_TXD_R (65) 
UART_T8_NODE1_RXD_R (65) 
UART_T8_NODE1_TXD_R (65) 
UART_T8_NODE4_RXD_R (65) 
UART_T8_NODE4_TXD_R (65) 
UART_T8_NODE3_RXD_R (65) 
UART_T8_NODE3_TXD_R (65) 
T6_NODE1_EN_R (63) 
T6_NODE2_EN_R (63) 
T6_NODE3_EN_R (63) 
T6_NODE4_EN_R (63) 
UART_T6_NODE1_RXD_R (64) 
UART_T6_NODE1_TXD_R (64) 
UART_T6_NODE3_RXD_R (64) 
UART_T6_NODE3_TXD_R (64) 
UART_T6_NODE2_RXD_R (64) 
UART_T6_NODE2_TXD_R (64) 
UART_T6_NODE4_RXD_R (64) 
UART_T6_NODE4_TXD_R (64) UART_T5_NODE2_RXD_R (64) 
UART_T5_NODE2_TXD_R (64) 
UART_T5_NODE3_RXD_R (64) 
UART_T5_NODE3_TXD_R (64) 
LAN1_P3_P (55) 
LAN1_P3_N (55) 
I2C_PSU2_R_SCL (62) 
I2C_PSU2_R_SDA (62) 
LAN1_P4_P (55) 
LAN1_P4_N (55) 
LAN1_P1_P (55) 
LAN1_P1_N (55) 
LAN1_P2_P (55) 
LAN1_P2_N (55) 
MATE_R_N (62) 
T5_NODE3_EN_R (63) 
T5_NODE4_EN_R (63) 
UART_T5_NODE1_RXD_R (64) 
UART_T5_NODE1_TXD_R (64) 
CM_PWR_CTL_IN (66) 
UART_RI_RP6_L_N (56) 
UART_RX_RP6_L (56) 
UART_DTR_RP6_L_N (56) 
UART_RTS_RP6_L_N (56) 
UART_TX_RP6_L (56) 
UART_RTS_RP5_L_N 
UART_RX_RP5_L 
UART_TX_RP5_L 
UART_DTR_RP5_L_N (56) 
T4_NODE1_EN_R (63) 
T4_NODE2_EN_R (63) 
T4_NODE3_EN_R (63) 
T4_NODE4_EN_R (63) 
UART_T4_NODE1_RXD_R (64) 
UART_T4_NODE1_TXD_R (64) 
UART_T4_NODE2_RXD_R (64) 
UART_T4_NODE2_TXD_R (64) 
UART_T4_NODE4_RXD_R (64) 
UART_T4_NODE4_TXD_R (64) 
UART_T4_NODE3_RXD_R (64) 
UART_T4_NODE3_TXD_R (64) 
T2_NODE1_EN_R (63) 
T2_NODE2_EN_R (63) 
T2_NODE3_EN_R (63) 
T2_NODE4_EN_R (63) 
UART_T2_NODE1_RXD_R (64) 
UART_T2_NODE2_RXD_R (64) 
UART_T2_NODE2_TXD_R (64) 
UART_T2_NODE1_TXD_R (64) 
UART_T2_NODE4_RXD_R (64) 
UART_T2_NODE4_TXD_R (64) 
UART_T2_NODE3_RXD_R (64) 
UART_T2_NODE3_TXD_R (64) 
I2C_PSU1_R_SCL (62) 
I2C_PSU1_R_SDA (62) 
PSU1_AC_OK_R (62) 
PSU2_AC_OK_R (62) 
PSU3_AC_OK_R (62) 
PSU4_AC_OK_R (62) 
PSU5_AC_OK_R (62) 
PSU6_AC_OK_R (62) 
UART_T5_NODE4_RXD_R (64) 
UART_T5_NODE4_TXD_R (64) 
T3_NODE1_EN_R (63) 
T3_NODE2_EN_R (63) 
T3_NODE3_EN_R (63) 
T3_NODE4_EN_R (63) 
UART_T3_NODE1_RXD_R (64) 
UART_T3_NODE1_TXD_R (64) 
UART_T3_NODE2_RXD_R (64) 
UART_T3_NODE2_TXD_R (64) 
UART_T3_NODE3_RXD_R (64) 
UART_T3_NODE3_TXD_R (64) 
UART_T3_NODE4_RXD_R (64) 
UART_T3_NODE4_TXD_R (64) 
T1_NODE1_EN_R (63) 
T1_NODE2_EN_R (63) 
T1_NODE3_EN_R (63) 
T1_NODE4_EN_R (63) 
UART_T1_NODE2_RXD_R (64) 
UART_T1_NODE2_TXD_R (64) 
UART_T1_NODE3_RXD_R (64) 
UART_T1_NODE3_TXD_R (64) 
UART_T1_NODE4_RXD_R (64) 
UART_T1_NODE4_TXD_R (64) 
UART_T1_NODE1_RXD_R (64) 
UART_T1_NODE1_TXD_R (64) 
PSU1_DC_OK_R 
PSU2_DC_OK_R 
PSU3_DC_OK_R 
PSU4_DC_OK_R 
PSU5_DC_OK_R 
PSU6_DC_OK_R 
UART_RTS_P1_L_N 
UART_TX_P1_L 
UART_CTS_P1_L_N (56) 
UART_DSR_P1_L_N 
UART_RX_P1_L 
UART_DTR_P1_L_N (56) 
UART_RTS_P5_L_N 
UART_DSR_P5_L_N 
UART_CTS_P5_L_N 
UART_TX_P5_L 
UART_RI_P5_L_N (56) 
UART_RX_P5_L 
UART_DTR_P5_L_N (56) 
UART_RTS_P6_L_N 
UART_RX_P6_L 
UART_DTR_P6_L_N (56) 
UART_TX_P6_L 
UART_RI_P6_L_N (56)
UART_DSR_P6_L_N (56) 
UART_CTS_P6_L_N (56) 
UART_RTS_P2_L_N 
UART_DSR_P2_L_N 
UART_RX_P2_L 
UART_DTR_P2_L_N (56) 
UART_TX_P2_L 
UART_CTS_P2_L_N (56) 
UART_RI_RP5_L_N (56) 
P3V3_NODE1 
P12V_PDB 
P12V_PDB 
Title 
Size Document Number Rev
Date: Sheet 
of 
Gold Finger 1A
Chassis Manager Assembly V1 
Cloud Server Infrastructure Engineering
C
61 85Monday, January 27, 2014 
Title 
Size Document Number Rev
Date: Sheet 
of 
Gold Finger 1A
Chassis Manager Assembly V1 
Cloud Server Infrastructure Engineering
C
61 85Monday, January 27, 2014 
Title 
Size Document Number Rev
Date: Sheet 
of 
Gold Finger 1A
Chassis Manager Assembly V1 
Cloud Server Infrastructure Engineering
C
61 85Monday, January 27, 2014 
TP10 1 R1333 100 
R1332 100 
TP11 1
R1334 100 
TP9 1
KEY
J18 
GOLD_PCI-E_X16 
NI 
12V_3 B1 
12V_4 B2 
RSVD1 B3 
GND34 B4 
SMCLK B5 
SMDATA B6 
GND35 B7 
3.3V_3 B8 
JTAG1 B9 
3.3VAUX B10 
WAKE_N B11 
HSOP8+ B50 
HSOP8- B51 
GND53 B52 
GND54 B53 
HSOP9+ B54 
HSOP9- B55 
GND55 B56 
GND56 B57 
HSOP10+ B58 
HSOP10- B59 
GND57 B60 
GND58 B61 
HSOP11+ B62 
HSOP11- B63 
GND59 B64 
GND60 B65 
HSOP12+ B66 
HSOP12- B67 
GND61 B68 
GND62 B69 
HSOP13+ B70 
HSOP13- B71 
GND63 B72 
GND64 B73 
HSOP14+ B74 
HSOP14- B75 
GND65 B76 
GND66 B77 
HSOP15+ B78 
HSOP15- B79 
GND67 B80 
PRSNT2_N-4 B81 
RSVD4 B82 
HSOP4+ B33 
HSOP4- B34 
GND45 B35 
GND46 B36 
HSOP5+ B37 
HSOP5- B38 
GND47 B39 
GND48 B40 
HSOP6+ B41 
HSOP6- B42 
GND49 B43 
GND50 B44 
HSOP7+ B45 
HSOP7- B46 
GND51 B47 
PRSNT2_N-3 B48 
GND52 B49 
HSOP1+ B19 
HSOP1- B20 
GND39 B21 
GND40 B22 
HSOP2+ B23 
HSOP2- B24 
GND41 B25 
GND42 B26 
HSOP3+ B27 
HSOP3- B28 
GND43 B29 
RSVD3 B30 
PRSNT2_N-2 B31 
GND44 B32 
RSVD2 B12 
GND36 B13 
HSOP0+ B14 
HSOP0- B15 
GND37 B16 
PRSNT2_N-1 B17 
GND38 B18 
PRSNT1_N A1 
12V_1 A2 
12V_2 A3 
GND1 A4 
JTAG2 A5 
JTAG3 A6 
JTAG4 A7 
JTAG5 A8 
3.3V_1 A9 
3.3V_2 A10 
PWRGD A11 
RSVD8 A50 
GND19 A51 
HSIP8+ A52 
HSIP8- A53 
GND20 A54 
GND21 A55 
HSIP9+ A56 
HSIP9- A57 
GND22 A58 
GND23 A59 
HSIP10+ A60 
HSIP10- A61 
GND24 A62 
GND25 A63 
HSIP11+ A64 
HSIP11- A65 
GND26 A66 
RSVD9 A67 
HSIP12+ A68 
HSIP12- A69 
GND27 A70 
GND28 A71 
HSIP13+ A72 
HSIP13- A73 
GND29 A74 
GND30 A75 
HSIP14 A76 
HSIP14- A77 
GND31 A78 
GND32 A79 
HSIP15+ A80 
HSIP15- A81 
GND33 A82 
RSVD7 A33 
GND11 A34 
HSIP4+ A35 
HSIP4- A36 
GND12 A37 
GND13 A38 
HSIP5+ A39 
HSIP5- A40 
GND14 A41 
GND15 A42 
HSIP6+ A43 
HSIP6- A44 
GND16 A45 
GND17 A46 
HSIP7+ A47 
HSIP7- A48 
GND18 A49 
RSVD5 A19 
GND5 A20 
HSIP1+ A21 
HSIP1- A22 
GND6 A23 
GND7 A24 
HSIP2+ A25 
HSIP2- A26 
GND8 A27 
GND9 A28 
HSIP3+ A29 
HSIP3- A30 
GND10 A31 
RSVD6 A32 
GND2 A12 
REFCLK+ A13 
REFCLK- A14 
GND3 A15 
HSIP0+ A16 
HSIP0- A17 
GND4 A18 
KEY
J35 
GOLD_PCI-E_X16 
NI 
12V_3 B1 
12V_4 B2 
RSVD1 B3 
GND34 B4 
SMCLK B5 
SMDATA B6 
GND35 B7 
3.3V_3 B8 
JTAG1 B9 
3.3VAUX B10 
WAKE_N B11 
HSOP8+ B50 
HSOP8- B51 
GND53 B52 
GND54 B53 
HSOP9+ B54 
HSOP9- B55 
GND55 B56 
GND56 B57 
HSOP10+ B58 
HSOP10- B59 
GND57 B60 
GND58 B61 
HSOP11+ B62 
HSOP11- B63 
GND59 B64 
GND60 B65 
HSOP12+ B66 
HSOP12- B67 
GND61 B68 
GND62 B69 
HSOP13+ B70 
HSOP13- B71 
GND63 B72 
GND64 B73 
HSOP14+ B74 
HSOP14- B75 
GND65 B76 
GND66 B77 
HSOP15+ B78 
HSOP15- B79 
GND67 B80 
PRSNT2_N-4 B81 
RSVD4 B82 
HSOP4+ B33 
HSOP4- B34 
GND45 B35 
GND46 B36 
HSOP5+ B37 
HSOP5- B38 
GND47 B39 
GND48 B40 
HSOP6+ B41 
HSOP6- B42 
GND49 B43 
GND50 B44 
HSOP7+ B45 
HSOP7- B46 
GND51 B47 
PRSNT2_N-3 B48 
GND52 B49 
HSOP1+ B19 
HSOP1- B20 
GND39 B21 
GND40 B22 
HSOP2+ B23 
HSOP2- B24 
GND41 B25 
GND42 B26 
HSOP3+ B27 
HSOP3- B28 
GND43 B29 
RSVD3 B30 
PRSNT2_N-2 B31 
GND44 B32 
RSVD2 B12 
GND36 B13 
HSOP0+ B14 
HSOP0- B15 
GND37 B16 
PRSNT2_N-1 B17 
GND38 B18 
PRSNT1_N A1 
12V_1 A2 
12V_2 A3 
GND1 A4 
JTAG2 A5 
JTAG3 A6 
JTAG4 A7 
JTAG5 A8 
3.3V_1 A9 
3.3V_2 A10 
PWRGD A11 
RSVD8 A50 
GND19 A51 
HSIP8+ A52 
HSIP8- A53 
GND20 A54 
GND21 A55 
HSIP9+ A56 
HSIP9- A57 
GND22 A58 
GND23 A59 
HSIP10+ A60 
HSIP10- A61 
GND24 A62 
GND25 A63 
HSIP11+ A64 
HSIP11- A65 
GND26 A66 
RSVD9 A67 
HSIP12+ A68 
HSIP12- A69 
GND27 A70 
GND28 A71 
HSIP13+ A72 
HSIP13- A73 
GND29 A74 
GND30 A75 
HSIP14 A76 
HSIP14- A77 
GND31 A78 
GND32 A79 
HSIP15+ A80 
HSIP15- A81 
GND33 A82 
RSVD7 A33 
GND11 A34 
HSIP4+ A35 
HSIP4- A36 
GND12 A37 
GND13 A38 
HSIP5+ A39 
HSIP5- A40 
GND14 A41 
GND15 A42 
HSIP6+ A43 
HSIP6- A44 
GND16 A45 
GND17 A46 
HSIP7+ A47 
HSIP7- A48 
GND18 A49 
RSVD5 A19 
GND5 A20 
HSIP1+ A21 
HSIP1- A22 
GND6 A23 
GND7 A24 
HSIP2+ A25 
HSIP2- A26 
GND8 A27 
GND9 A28 
HSIP3+ A29 
HSIP3- A30 
GND10 A31 
RSVD6 A32 
GND2 A12 
REFCLK+ A13 
REFCLK- A14 
GND3 A15 
HSIP0+ A16 
HSIP0- A17 
GND4 A18 
R1331 100 
TP12 1



5
5
4
4
3
3
2
2
1
1
D D
C C
B B
A A
PSU2_DC_OK_R_BUF 
PSU4_DC_OK_R_BUF 
PSU2_AC_OK_R 
PSU2_DC_OK_R 
PSU4_DC_OK_R 
PSU3_DC_OK_R 
PSU1_DC_OK_R 
PSU6_DC_OK_R 
PSU5_DC_OK_R 
PSU3_DC_OK_R_BUF PSU5_DC_OK_R_BUF 
PSU6_DC_OK_R_BUF 
PSU4_DC_OK_R_BUF 
PSU5_DC_OK_R_BUF 
PSU4_AC_OK_R 
PSU3_AC_OK_R 
PSU2_DC_OK_R_BUF 
PSU1_AC_OK_R 
PSU6_AC_OK_R 
PSU5_AC_OK_R 
PSU6_DC_OK_R_BUF 
PSU1_DC_OK_R_BUF 
PSU3_DC_OK_R_BUF 
PSU1_DC_OK_R_BUF 
PSU5_AC_OK (58) PSU5_AC_OK_R (61) 
PSU6_AC_OK (58) PSU6_AC_OK_R (61) 
PSU1_AC_OK (58) PSU1_AC_OK_R (61) 
PSU2_AC_OK (58) PSU2_AC_OK_R (61) 
PSU3_AC_OK (58) PSU3_AC_OK_R (61) 
PSU4_AC_OK (58) PSU4_AC_OK_R (61) 
PSU5_DC_OK_R 
PSU6_DC_OK_R 
PSU1_DC_OK_R 
PSU2_DC_OK_R 
PSU3_DC_OK_R 
PSU4_DC_OK_R 
I2C_PSU3_R_SDA (61) I2C_PSU3_SDA (58) 
I2C_PSU3_R_SCL (61) I2C_PSU3_SCL (58) 
I2C_PSU1_R_SDA (61) I2C_PSU1_SDA (58) 
I2C_PSU1_R_SCL (61) I2C_PSU1_SCL (58) 
I2C_PSU2_R_SDA (61) I2C_PSU2_SDA (58) 
I2C_PSU2_R_SCL (61) I2C_PSU2_SCL (58) 
FAN4_TACH_R (61) FAN4_TACH 
FAN5_TACH_R (61) FAN5_TACH 
FAN_PWM_R FAN_PWM (59) 
FAN1_TACH_R FAN1_TACH 
FAN2_TACH_R FAN2_TACH 
FAN3_TACH_R FAN3_TACH 
FAN6_TACH_R (61) FAN6_TACH 
MATE_N (66) MATE_R_N (61) 
PSU_ALERT_N PSU_ALERT_R_N 
I2C_PDB_R_SCL (61) I2C_PDB_SCL 
I2C_PDB_R_SDA (61) I2C_PDB_SDA (58) 
PSU1_DC_OK (58) 
PSU2_DC_OK (58) 
PSU3_DC_OK (58) 
PSU4_DC_OK (58) 
PSU5_DC_OK (58) 
PSU6_DC_OK (58) 
PSU1_DC_OK_R_BUF (66) 
PSU2_DC_OK_R_BUF (66) 
PSU3_DC_OK_R_BUF (66) 
PSU4_DC_OK_R_BUF (66) 
PSU5_DC_OK_R_BUF (66) 
PSU6_DC_OK_R_BUF (66) 
P3V3_NODE1 
P3V3_NODE1 
P3V3_NODE1 
P3V3_NODE1 
P3V3_NODE1 
P3V3_NODE1 
P3V3_NODE1 
P3V3_NODE1 
P3V3_NODE1 
P3V3_NODE1 
P3V3_NODE1 
P3V3_NODE1 
Title 
Size Document Number Rev
Date: Sheet 
of 
Filter 1 1A
Chassis Manager Assembly V1 
Cloud Server Infrastructure Engineering
C
62 85Monday, January 27, 2014 
Title 
Size Document Number Rev
Date: Sheet 
of 
Filter 1 1A
Chassis Manager Assembly V1 
Cloud Server Infrastructure Engineering
C
62 85Monday, January 27, 2014 
Title 
Size Document Number Rev
Date: Sheet 
of 
Filter 1 1A
Chassis Manager Assembly V1 
Cloud Server Infrastructure Engineering
C
62 85Monday, January 27, 2014 
R852 100K 
R0402 5% 
C610 10PF 
C0G 50V 
R848 100K 
R0402 5% 
U84 
74LVC1G17GV 
VCC 5
A2
GND 3
Y 4
NC 1
R822 33 
R0402 5% 
U88 
74LVC1G17GV 
VCC 5
A2
GND 3
Y 4
NC 1
R826 33 
R0402 5% 
C597 10PF 
C0G 50V 
C612 0.1UF 
X7R 16V 
U87 
74LVC1G17GV 
VCC 5
A2
GND 3
Y 4
NC 1
C593 10PF 
C0G 50V 
R832 100 
R0402 1% 
R841 33 
R0402 5% 
C604 100PF 
NPO 50V 
R857 100K 
R0402 5% 
R846 33 
R0402 5% 
R818 33 
R0402 5% 
R838 33 
R0402 5% 
R842 33 
R0402 5% 
C607 100PF 
NPO 50V 
R845 100K 
R0402 5% 
R839 33 
R0402 5% 
R824 33 
R0402 5% 
R828 33 
R0402 5% 
C616 
0.1UF 
16V 
C0402 
R858 100K 
R0402 5% 
C589 10PF 
C0G 50V 
C601 0.1UF 
X7R 16V 
C621 
0.1UF 
16V 
C0402 
C609 0.1UF 
X7R 16V 
R830 33 
R0402 5% 
C614 100PF 
NPO 50V 
C608 100PF 
NPO 50V 
C617 
0.1UF 
16V 
C0402 
R854 100K 
R0402 5% 
R827 33 
R0402 5% 
U85 
74LVC1G17GV 
VCC 5
A2
GND 3
Y 4
NC 1
R1224 4.7K 
R849 100K 
R0402 5% 
R843 100 
R0402 1% 
C588 100PF 
NPO 50V 
C611 100PF 
NPO 50V 
R821 33 
R0402 5% 
C605 100PF 
NPO 50V 
R1223 4.7K 
U86 
74LVC1G17GV 
VCC 5
A2
GND 3
Y 4
NC 1
C619 
0.1UF 
16V 
C0402 
C613 10PF 
C0G 50V 
R833 33 
R0402 5% 
R1219 4.7K 
R847 100 
R0402 1% 
R853 100K 
R0402 5% 
R844 33 
R0402 5% 
R823 33 
R0402 5% 
C603 0.1UF 
X7R 16V 
C591 10PF 
C0G 50V 
C587 10PF 
C0G 50V 
R1222 4.7K C595 10PF 
C0G 50V 
R850 100K 
R0402 5% 
R834 100 
R0402 1% 
R820 33 
R0402 5% 
R835 33 
R0402 5% 
C620 
0.1UF 
16V 
C0402 
R856 100K 
R0402 5% 
C618 
0.1UF 
16V 
C0402 
R837 100 
R0402 1% 
C615 0.1UF 
X7R 16V 
C606 0.1UF 
X7R 16V 
U89 
74LVC1G17GV 
VCC 5
A2
GND 3
Y 4
NC 1
R855 100K 
R0402 5% 
R1221 4.7K 
R840 100 
R0402 1% 
R836 33 
R0402 5% 
R829 33 
R0402 5% 
C602 100PF 
NPO 50V 
C600 100PF 
NPO 50V 
R825 33 
R0402 5% 
R851 100K 
R0402 5% 
R831 33 
R0402 5% 
R1220 4.7K 
R819 33 
R0402 5% 



5
5
4
4
3
3
2
2
1
1
D D
C C
B B
A A
T12_NODE1_EN_R (61) T12_NODE1_EN 
T12_NODE2_EN_R (61) T12_NODE2_EN 
T12_NODE3_EN_R (61) T12_NODE3_EN 
T12_NODE4_EN_R (61) T12_NODE4_EN 
T11_NODE1_EN_R (61) T11_NODE1_EN 
T11_NODE2_EN_R (61) T11_NODE2_EN 
T11_NODE3_EN_R (61) T11_NODE3_EN 
T11_NODE4_EN_R (61) T11_NODE4_EN 
T10_NODE1_EN_R (61) T10_NODE1_EN 
T10_NODE2_EN_R (61) T10_NODE2_EN 
T10_NODE3_EN_R (61) T10_NODE3_EN 
T10_NODE4_EN_R (61) T10_NODE4_EN 
T9_NODE1_EN_R (61) T9_NODE1_EN 
T9_NODE2_EN_R (61) T9_NODE2_EN 
T9_NODE3_EN_R (61) T9_NODE3_EN 
T9_NODE4_EN_R (61) T9_NODE4_EN 
T8_NODE1_EN_R (61) T8_NODE1_EN 
T8_NODE2_EN_R (61) T8_NODE2_EN 
T8_NODE3_EN_R (61) T8_NODE3_EN 
T8_NODE4_EN_R (61) T8_NODE4_EN 
T7_NODE1_EN_R (61) T7_NODE1_EN 
T7_NODE2_EN_R (61) T7_NODE2_EN 
T7_NODE3_EN_R (61) T7_NODE3_EN 
T7_NODE4_EN_R (61) T7_NODE4_EN 
T6_NODE1_EN_R (61) T6_NODE1_EN 
T6_NODE2_EN_R (61) T6_NODE2_EN 
T6_NODE3_EN_R (61) T6_NODE3_EN 
T6_NODE4_EN_R (61) T6_NODE4_EN 
T5_NODE1_EN_R (61) T5_NODE1_EN 
T5_NODE2_EN_R (61) T5_NODE2_EN 
T5_NODE3_EN_R (61) T5_NODE3_EN 
T5_NODE4_EN_R (61) T5_NODE4_EN 
T4_NODE1_EN_R (61) T4_NODE1_EN 
T4_NODE2_EN_R (61) T4_NODE2_EN 
T4_NODE3_EN_R (61) T4_NODE3_EN 
T4_NODE4_EN_R (61) T4_NODE4_EN 
T2_NODE1_EN_R (61) T2_NODE1_EN 
T2_NODE2_EN_R (61) T2_NODE2_EN 
T2_NODE3_EN_R (61) T2_NODE3_EN 
T2_NODE4_EN_R (61) T2_NODE4_EN 
T1_NODE1_EN_R (61) T1_NODE1_EN 
T1_NODE2_EN_R (61) T1_NODE2_EN 
T1_NODE3_EN_R (61) T1_NODE3_EN 
T1_NODE4_EN_R (61) T1_NODE4_EN 
T3_NODE1_EN_R (61) T3_NODE1_EN 
T3_NODE2_EN_R (61) T3_NODE2_EN 
T3_NODE3_EN_R (61) T3_NODE3_EN 
T3_NODE4_EN_R (61) T3_NODE4_EN 
Title 
Size Document Number Rev
Date: Sheet 
of 
Filter 2 1A
Chassis Manager Assembly V1 
Cloud Server Infrastructure Engineering
C
63 85Monday, January 27, 2014 
Title 
Size Document Number Rev
Date: Sheet 
of 
Filter 2 1A
Chassis Manager Assembly V1 
Cloud Server Infrastructure Engineering
C
63 85Monday, January 27, 2014 
Title 
Size Document Number Rev
Date: Sheet 
of 
Filter 2 1A
Chassis Manager Assembly V1 
Cloud Server Infrastructure Engineering
C
63 85Monday, January 27, 2014 
R879 33 
R0402 1% 
C634 100PF 
NPO 50V 
R865 33 
R0402 1% 
C645 100PF 
NPO 50V 
R899 33 
R0402 1% 
C651 100PF 
NPO 50V 
C666 100PF 
NPO 50V 
C664 100PF 
NPO 50V 
C630 100PF 
NPO 50V 
C669 100PF 
NPO 50V 
C636 100PF 
NPO 50V 
R884 33 
R0402 1% 
R862 33 
R0402 1% 
R869 33 
R0402 1% 
R888 33 
R0402 1% 
R900 33 
R0402 1% 
R901 33 
R0402 1% 
C659 100PF 
NPO 50V 
C627 100PF 
NPO 50V 
C658 100PF 
NPO 50V 
C633 100PF 
NPO 50V 
R859 33 
R0402 1% 
R882 33 
R0402 1% 
R891 33 
R0402 1% 
R883 33 
R0402 1% 
C638 100PF 
NPO 50V 
C649 100PF 
NPO 50V 
R868 33 
R0402 1% 
R893 33 
R0402 1% 
R873 33 
R0402 1% 
R877 33 
R0402 1% 
R876 33 
R0402 1% 
R880 33 
R0402 1% 
C643 100PF 
NPO 50V 
C660 100PF 
NPO 50V 
C654 100PF 
NPO 50V 
C631 100PF 
NPO 50V 
R864 33 
R0402 1% 
C657 100PF 
NPO 50V 
R881 33 
R0402 1% 
R860 33 
R0402 1% 
C640 100PF 
NPO 50V 
R872 33 
R0402 1% 
C648 100PF 
NPO 50V 
C628 100PF 
NPO 50V 
C622 100PF 
NPO 50V 
R898 33 
R0402 1% 
C656 100PF 
NPO 50V 
R871 33 
R0402 1% 
R874 33 
R0402 1% 
R863 33 
R0402 1% 
C629 100PF 
NPO 50V 
R890 33 
R0402 1% 
R895 33 
R0402 1% 
C653 100PF 
NPO 50V 
C662 100PF 
NPO 50V 
C663 100PF 
NPO 50V 
C661 100PF 
NPO 50V 
R905 33 
R0402 1% 
R866 33 
R0402 1% 
C639 100PF 
NPO 50V 
R887 33 
R0402 1% 
C625 100PF 
NPO 50V 
C632 100PF 
NPO 50V 
R867 33 
R0402 1% 
C665 100PF 
NPO 50V 
C644 100PF 
NPO 50V 
C655 100PF 
NPO 50V 
C637 100PF 
NPO 50V 
R885 33 
R0402 1% 
R897 33 
R0402 1% 
R861 33 
R0402 1% 
R902 33 
R0402 1% 
C641 100PF 
NPO 50V 
C635 100PF 
NPO 50V 
C652 100PF 
NPO 50V 
C667 100PF 
NPO 50V 
R892 33 
R0402 1% 
C623 100PF 
NPO 50V 
C626 100PF 
NPO 50V 
R878 33 
R0402 1% 
C650 100PF 
NPO 50V 
C624 100PF 
NPO 50V 
R894 33 
R0402 1% 
R906 33 
R0402 1% 
R870 33 
R0402 1% 
R904 33 
R0402 1% 
C642 100PF 
NPO 50V 
R896 33 
R0402 1% 
R875 33 
R0402 1% 
R903 33 
R0402 1% 
C647 100PF 
NPO 50V 
R889 33 
R0402 1% 
R886 33 
R0402 1% 
C668 100PF 
NPO 50V 
C646 100PF 
NPO 50V 



5
5
4
4
3
3
2
2
1
1
D D
C C
B B
A A
UART_T6_NODE3_RXD_R (61) 
UART_T6_NODE4_RXD_R (61) 
UART_T6_NODE3_RXD 
UART_T6_NODE4_RXD 
UART_T6_NODE3_TXD_R (61) UART_T6_NODE3_TXD 
UART_T6_NODE4_TXD_R (61) UART_T6_NODE4_TXD 
UART_T4_NODE3_RXD_R (61) 
UART_T4_NODE4_RXD_R (61) 
UART_T4_NODE3_RXD 
UART_T4_NODE4_RXD 
UART_T4_NODE3_TXD_R (61) UART_T4_NODE3_TXD 
UART_T4_NODE4_TXD_R (61) UART_T4_NODE4_TXD 
UART_T4_NODE1_RXD_R (61) 
UART_T4_NODE2_RXD_R (61) 
UART_T4_NODE1_RXD 
UART_T4_NODE2_RXD 
UART_T4_NODE1_TXD_R (61) UART_T4_NODE1_TXD 
UART_T4_NODE2_TXD_R (61) UART_T4_NODE2_TXD 
UART_T3_NODE3_RXD_R (61) 
UART_T3_NODE4_RXD_R (61) 
UART_T3_NODE3_RXD 
UART_T3_NODE4_RXD 
UART_T3_NODE3_TXD_R (61) UART_T3_NODE3_TXD 
UART_T3_NODE4_TXD_R (61) UART_T3_NODE4_TXD 
UART_T3_NODE1_RXD_R (61) 
UART_T3_NODE2_RXD_R (61) 
UART_T3_NODE1_RXD 
UART_T3_NODE2_RXD 
UART_T3_NODE1_TXD_R (61) UART_T3_NODE1_TXD 
UART_T3_NODE2_TXD_R (61) UART_T3_NODE2_TXD 
UART_T2_NODE3_RXD_R (61) 
UART_T2_NODE4_RXD_R (61) 
UART_T2_NODE3_RXD (60) 
UART_T2_NODE4_RXD (60) 
UART_T2_NODE3_TXD_R (61) UART_T2_NODE3_TXD (60) 
UART_T2_NODE4_TXD_R (61) UART_T2_NODE4_TXD (60) 
UART_T2_NODE1_RXD_R (61) 
UART_T2_NODE2_RXD_R (61) 
UART_T2_NODE1_RXD (60) 
UART_T2_NODE2_RXD (60) 
UART_T2_NODE1_TXD_R (61) UART_T2_NODE1_TXD (60) 
UART_T6_NODE1_RXD_R (61) 
UART_T6_NODE2_RXD_R (61) 
UART_T6_NODE1_RXD 
UART_T6_NODE2_RXD 
UART_T6_NODE1_TXD_R (61) UART_T6_NODE1_TXD 
UART_T2_NODE2_TXD_R (61) UART_T2_NODE2_TXD (60) UART_T6_NODE2_TXD_R (61) UART_T6_NODE2_TXD 
UART_T1_NODE3_RXD_R (61) 
UART_T1_NODE4_RXD_R (61) 
UART_T1_NODE3_RXD (60) 
UART_T1_NODE4_RXD (60) 
UART_T1_NODE3_TXD_R (61) UART_T1_NODE3_TXD (60) 
UART_T1_NODE4_TXD_R (61) UART_T1_NODE4_TXD (60) 
UART_T1_NODE1_RXD_R (61) 
UART_T1_NODE2_RXD_R (61) 
UART_T1_NODE1_RXD (60) 
UART_T1_NODE2_RXD (60) 
UART_T1_NODE1_TXD_R (61) UART_T1_NODE1_TXD (60) 
UART_T5_NODE3_RXD_R (61) 
UART_T5_NODE4_RXD_R (61) 
UART_T5_NODE3_RXD 
UART_T5_NODE4_RXD 
UART_T1_NODE2_TXD_R (61) 
UART_T5_NODE3_TXD_R (61) 
UART_T1_NODE2_TXD (60) 
UART_T5_NODE3_TXD 
UART_T5_NODE4_TXD_R (61) UART_T5_NODE4_TXD 
UART_T5_NODE1_RXD_R (61) 
UART_T5_NODE2_RXD_R (61) 
UART_T5_NODE1_RXD 
UART_T5_NODE2_RXD 
UART_T5_NODE1_TXD_R (61) UART_T5_NODE1_TXD 
UART_T5_NODE2_TXD_R (61) UART_T5_NODE2_TXD 
Title 
Size Document Number Rev
Date: Sheet 
of 
Filter 3 1A
Chassis Manager Assembly V1 
Cloud Server Infrastructure Engineering
C
64 85Monday, January 27, 2014 
Title 
Size Document Number Rev
Date: Sheet 
of 
Filter 3 1A
Chassis Manager Assembly V1 
Cloud Server Infrastructure Engineering
C
64 85Monday, January 27, 2014 
Title 
Size Document Number Rev
Date: Sheet 
of 
Filter 3 1A
Chassis Manager Assembly V1 
Cloud Server Infrastructure Engineering
C
64 85Monday, January 27, 2014 
R911 33 
R0402 1% 
R943 33 
R0402 1% 
C696 100PF 
NPO 50V 
C707 100PF 
NPO 50V 
R912 33 
R0402 1% 
C694 100PF 
NPO 50V 
C709 100PF 
NPO 50V 
R928 33 
R0402 1% 
R944 33 
R0402 1% 
C699 100PF 
NPO 50V 
R954 33 
R0402 1% 
R929 33 
R0402 1% 
R934 33 
R0402 1% 
R930 33 
R0402 1% 
C698 100PF 
NPO 50V 
C705 100PF 
NPO 50V 
R908 33 
R0402 1% 
R948 33 
R0402 1% 
C684 100PF 
NPO 50V 
C695 100PF 
NPO 50V 
C676 100PF 
NPO 50V 
R940 33 
R0402 1% 
R922 33 
R0402 1% 
R946 33 
R0402 1% 
R915 33 
R0402 1% 
C716 100PF 
NPO 50V 
C697 100PF 
NPO 50V 
R941 33 
R0402 1% 
C704 100PF 
NPO 50V 
C711 100PF 
NPO 50V 
C692 100PF 
NPO 50V 
R914 33 
R0402 1% 
C700 100PF 
NPO 50V 
R920 33 
R0402 1% 
R949 33 
R0402 1% 
R917 33 
R0402 1% 
C682 100PF 
NPO 50V 
R931 33 
R0402 1% 
R951 33 
R0402 1% 
C686 100PF 
NPO 50V 
R933 33 
R0402 1% 
R909 33 
R0402 1% 
C678 100PF 
NPO 50V 
C680 100PF 
NPO 50V 
R925 33 
R0402 1% 
R945 33 
R0402 1% 
R936 33 
R0402 1% 
C701 100PF 
NPO 50V 
C691 100PF 
NPO 50V 
C702 100PF 
NPO 50V 
R947 33 
R0402 1% 
R924 33 
R0402 1% 
C670 100PF 
NPO 50V 
C703 100PF 
NPO 50V 
C672 100PF 
NPO 50V 
R923 33 
R0402 1% 
C687 100PF 
NPO 50V 
C681 100PF 
NPO 50V 
R916 33 
R0402 1% 
C683 100PF 
NPO 50V 
R932 33 
R0402 1% 
C671 100PF 
NPO 50V 
R942 33 
R0402 1% 
C714 100PF 
NPO 50V 
C689 100PF 
NPO 50V 
C685 100PF 
NPO 50V 
R910 33 
R0402 1% 
R939 33 
R0402 1% 
C706 100PF 
NPO 50V 
C677 100PF 
NPO 50V 
C713 100PF 
NPO 50V 
R927 33 
R0402 1% 
C674 100PF 
NPO 50V 
C688 100PF 
NPO 50V 
C679 100PF 
NPO 50V 
C712 100PF 
NPO 50V 
R926 33 
R0402 1% 
R918 33 
R0402 1% 
R913 33 
R0402 1% 
R919 33 
R0402 1% 
C717 100PF 
NPO 50V 
R935 33 
R0402 1% 
R937 33 
R0402 1% 
R938 33 
R0402 1% 
C675 100PF 
NPO 50V 
C715 100PF 
NPO 50V 
R921 33 
R0402 1% 
C673 100PF 
NPO 50V 
R950 33 
R0402 1% 
R907 33 
R0402 1% 
C710 100PF 
NPO 50V 
R953 33 
R0402 1% 
C693 100PF 
NPO 50V 
C690 100PF 
NPO 50V 
C708 100PF 
NPO 50V 
R952 33 
R0402 1% 



5
5
4
4
3
3
2
2
1
1
D D
C C
B B
A A
UART_T12_NODE3_RXD_R (61) 
UART_T12_NODE4_RXD_R (61) 
UART_T12_NODE3_RXD 
UART_T12_NODE4_RXD 
UART_T12_NODE3_TXD_R (61) UART_T12_NODE3_TXD 
UART_T12_NODE4_TXD_R (61) UART_T12_NODE4_TXD 
UART_T12_NODE1_RXD_R (61) 
UART_T12_NODE2_RXD_R (61) 
UART_T12_NODE1_RXD 
UART_T12_NODE2_RXD 
UART_T12_NODE1_TXD_R (61) UART_T12_NODE1_TXD 
UART_T12_NODE2_TXD_R (61) UART_T12_NODE2_TXD 
UART_T11_NODE3_RXD_R (61) 
UART_T11_NODE4_RXD_R (61) 
UART_T11_NODE3_RXD 
UART_T11_NODE4_RXD 
UART_T11_NODE3_TXD_R (61) UART_T11_NODE3_TXD 
UART_T11_NODE4_TXD_R (61) UART_T11_NODE4_TXD 
UART_T11_NODE1_RXD_R (61) 
UART_T11_NODE2_RXD_R (61) 
UART_T11_NODE1_RXD 
UART_T11_NODE2_RXD 
UART_T11_NODE1_TXD_R (61) UART_T11_NODE1_TXD 
UART_T11_NODE2_TXD_R (61) UART_T11_NODE2_TXD 
UART_T9_NODE3_RXD_R (61) 
UART_T9_NODE4_RXD_R (61) 
UART_T9_NODE3_RXD 
UART_T9_NODE4_RXD 
UART_T9_NODE3_TXD_R (61) UART_T9_NODE3_TXD 
UART_T9_NODE4_TXD_R (61) UART_T9_NODE4_TXD 
UART_T9_NODE1_RXD_R (61) 
UART_T9_NODE2_RXD_R (61) 
UART_T9_NODE1_RXD 
UART_T9_NODE2_RXD 
UART_T9_NODE1_TXD_R (61) UART_T9_NODE1_TXD 
UART_T9_NODE2_TXD_R (61) UART_T9_NODE2_TXD 
UART_T8_NODE3_RXD_R (61) 
UART_T8_NODE4_RXD_R (61) 
UART_T8_NODE3_RXD (60) 
UART_T8_NODE4_RXD (60) 
UART_T8_NODE3_TXD_R (61) UART_T8_NODE3_TXD (60) 
UART_T8_NODE4_TXD_R (61) UART_T8_NODE4_TXD (60) 
UART_T8_NODE1_RXD_R (61) 
UART_T8_NODE2_RXD_R (61) 
UART_T8_NODE1_RXD (60) 
UART_T8_NODE2_RXD (60) 
UART_T8_NODE1_TXD_R (61) UART_T8_NODE1_TXD (60) 
UART_T8_NODE2_TXD_R (61) UART_T8_NODE2_TXD (60) 
UART_T7_NODE3_RXD_R (61) 
UART_T7_NODE4_RXD_R (61) 
UART_T7_NODE3_RXD (60) 
UART_T7_NODE4_RXD (60) 
UART_T7_NODE3_TXD_R (61) UART_T7_NODE3_TXD (60) 
UART_T7_NODE4_TXD_R (61) UART_T7_NODE4_TXD (60) 
UART_T7_NODE1_RXD_R (61) 
UART_T7_NODE2_RXD_R (61) 
UART_T7_NODE1_RXD (60) 
UART_T7_NODE2_RXD (60) 
UART_T7_NODE1_TXD_R (61) UART_T7_NODE1_TXD (60) 
UART_T7_NODE2_TXD_R (61) UART_T7_NODE2_TXD (60) 
UART_T10_NODE3_RXD_R (61) 
UART_T10_NODE4_RXD_R (61) 
UART_T10_NODE3_RXD 
UART_T10_NODE4_RXD 
UART_T10_NODE3_TXD_R (61) UART_T10_NODE3_TXD 
UART_T10_NODE4_TXD_R (61) UART_T10_NODE4_TXD 
UART_T10_NODE1_RXD_R (61) 
UART_T10_NODE2_RXD_R (61) 
UART_T10_NODE1_RXD 
UART_T10_NODE2_RXD 
UART_T10_NODE1_TXD_R (61) UART_T10_NODE1_TXD 
UART_T10_NODE2_TXD_R (61) UART_T10_NODE2_TXD 
Title 
Size Document Number Rev
Date: Sheet 
of 
Filter 4 1A
Chassis Manager Assembly V1 
Cloud Server Infrastructure Engineering
C
65 85Monday, January 27, 2014 
Title 
Size Document Number Rev
Date: Sheet 
of 
Filter 4 1A
Chassis Manager Assembly V1 
Cloud Server Infrastructure Engineering
C
65 85Monday, January 27, 2014 
Title 
Size Document Number Rev
Date: Sheet 
of 
Filter 4 1A
Chassis Manager Assembly V1 
Cloud Server Infrastructure Engineering
C
65 85Monday, January 27, 2014 
R968 33 
R0402 1% 
R993 33 
R0402 1% 
C752 100PF 
NPO 50V 
R963 33 
R0402 1% 
C753 100PF 
NPO 50V 
C720 100PF 
NPO 50V 
R986 33 
R0402 1% 
R981 33 
R0402 1% 
R965 33 
R0402 1% 
R997 33 
R0402 1% 
C743 100PF 
NPO 50V 
R982 33 
R0402 1% 
C762 100PF 
NPO 50V 
C761 100PF 
NPO 50V 
C722 100PF 
NPO 50V 
R983 33 
R0402 1% 
R1001 33 
R0402 1% 
R957 33 
R0402 1% 
C728 100PF 
NPO 50V 
R970 33 
R0402 1% 
C731 100PF 
NPO 50V 
R1000 33 
R0402 1% 
R964 33 
R0402 1% 
C723 100PF 
NPO 50V 
C758 100PF 
NPO 50V 
C737 100PF 
NPO 50V 
R1002 33 
R0402 1% 
R984 33 
R0402 1% 
R955 33 
R0402 1% 
C725 100PF 
NPO 50V 
R971 33 
R0402 1% 
C736 100PF 
NPO 50V 
C740 100PF 
NPO 50V 
C733 100PF 
NPO 50V 
C759 100PF 
NPO 50V 
C732 100PF 
NPO 50V 
C729 100PF 
NPO 50V 
C760 100PF 
NPO 50V 
R987 33 
R0402 1% 
R995 33 
R0402 1% 
R990 33 
R0402 1% 
C741 100PF 
NPO 50V 
R988 33 
R0402 1% 
C750 100PF 
NPO 50V 
C721 100PF 
NPO 50V 
R969 33 
R0402 1% 
R975 33 
R0402 1% 
C747 100PF 
NPO 50V 
R978 33 
R0402 1% 
C727 100PF 
NPO 50V 
R991 33 
R0402 1% 
R996 33 
R0402 1% 
C719 100PF 
NPO 50V 
C745 100PF 
NPO 50V 
C738 100PF 
NPO 50V 
C764 100PF 
NPO 50V 
C730 100PF 
NPO 50V 
C765 100PF 
NPO 50V 
C735 100PF 
NPO 50V 
R973 33 
R0402 1% 
R985 33 
R0402 1% 
R994 33 
R0402 1% 
R999 33 
R0402 1% 
C739 100PF 
NPO 50V 
C724 100PF 
NPO 50V 
C751 100PF 
NPO 50V 
C749 100PF 
NPO 50V 
C746 100PF 
NPO 50V 
R980 33 
R0402 1% 
R960 33 
R0402 1% 
C744 100PF 
NPO 50V 
R956 33 
R0402 1% 
R974 33 
R0402 1% 
C734 100PF 
NPO 50V 
R959 33 
R0402 1% 
R979 33 
R0402 1% 
C748 100PF 
NPO 50V 
R972 33 
R0402 1% 
C726 100PF 
NPO 50V 
R976 33 
R0402 1% 
R998 33 
R0402 1% 
R962 33 
R0402 1% 
C763 100PF 
NPO 50V 
C754 100PF 
NPO 50V 
R966 33 
R0402 1% 
R989 33 
R0402 1% 
C756 100PF 
NPO 50V 
R977 33 
R0402 1% 
C757 100PF 
NPO 50V 
C718 100PF 
NPO 50V 
R967 33 
R0402 1% 
R958 33 
R0402 1% 
R961 33 
R0402 1% 
C755 100PF 
NPO 50V 
C742 100PF 
NPO 50V 
R992 33 
R0402 1% 



5
5
4
4
3
3
2
2
1
1
D D
C C
B B
A A
Under voltage threshold / R1022 x (R1020 + R1022) 
= Under voltage protection 
1.3 / 2.55k X (2.55k + 16.5k) = 9.7V 
I2C Address = 0xE4 
Initial time 12ms, fault time 1ms 
CONNECT TO CPLD 
3.24v 
SMB_BMC_NODE1_HSC_ALERT_R_L 
VSENSE_HSC_NODE1 
VR_HSC_NODE1_GATE_R 
VR_HSC_NODE1_TIMER 
VR_HSC_NODE1_GATE 
PWRGD_NODE1_P12V_PG_R 
P12V_NODE1_PWRGD_EN 
PWRGD_NODE1_P12V_PG 
PSU_DC_OK_N 
P12V_AUX_EN 
MATE_N 
P12V_AUX_EN 
CM_PWR_CTL_IN_R
CM_PWR_CTL_IN_R 
MATE_N 
SMB_CPU_NODE1_BMC_CLK (18) 
SMB_CPU_NODE1_BMC_DAT (18,30) 
SMB_BMC_NODE1_HSC_ALERT_L (16) 
PWRGD_NODE1_P12V_PG (67) 
MATE_N (62) 
PSU1_DC_OK_R_BUF (62) PSU3_DC_OK_R_BUF (62) 
PSU6_DC_OK_R_BUF (62) PSU4_DC_OK_R_BUF (62) 
PSU5_DC_OK_R_BUF (62) 
PSU2_DC_OK_R_BUF (62) 
CM_PWR_CTL_IN (61) 
P12V_AUX 
P12V_PDB 
P12V_PDB 
P12V_AUX 
P3V3_SUS_NODE1 
AGND_HSC_NODE1 
AGND_HSC_NODE1 
AGND_HSC_NODE1 
AGND_HSC_NODE1 
AGND_HSC_NODE1 
AGND_HSC_NODE1 
P12V_AUX 
P12V_PDB 
P12V_PDB 
P12V_PDB 
P12V_PDB 
P12V_DBG 
Title 
Size Document Number Rev
Date: Sheet 
of 
Hot Plug 1A
Chassis Manager Assembly V1 
Cloud Server Infrastructure Engineering
C
66 85Monday, January 27, 2014 
Title 
Size Document Number Rev
Date: Sheet 
of 
Hot Plug 1A
Chassis Manager Assembly V1 
Cloud Server Infrastructure Engineering
C
66 85Monday, January 27, 2014 
Title 
Size Document Number Rev
Date: Sheet 
of 
Hot Plug 1A
Chassis Manager Assembly V1 
Cloud Server Infrastructure Engineering
C
66 85Monday, January 27, 2014 
R1006 
10K 
U101 
MAX809SEUR+ 
GND 1
RESET# 2
VCC 3
U96 
2N7002LT1G 
G
D S
D20 
BZX84C13-7-F 
C768 
0.1UF 
X7R 
16V 
U97 
2N7002LT1G 
G
D S
U99 
2N7002LT1G 
G
D S
R1022 
16.5K 
1% 
R0402 
NI 
R1012 
22.1K 
C781 
0.01UF 16V 
X7R 
C0402 
10% 
R1007 10K 
U93 
2N7002LT1G 
G
D S
R1025 0
R0603 5% 
R1070 
4.7K 
R0402 
5% 
C777 
0.1UF 
X7R 
16V 
C0402 
10% 
U92 
2N7002LT1G 
G
D S
C767 
0.1UF 
X7R 
16V 
CH4103K1B08 
U114 
2N7002LT1G 
G
D S
C775
0.1UF
X7R
16V
R1029 
100K 
R0402 
5% 
R1019 0
5% R2010 
R106 0 R0402 5% 
R1028 
5.11K 
1% 
R0402 
C770 
0.1UF 
X7R 
16V 
J36 
HEADER 1X2R 
1 2
S1 S2 S3 
G1 
D1 
Q22 
PH0925CL 
3
5 2
4
1
C779 
2200PF 
X7R 
10% 
50V 
C0402 
R1251 
100K 
R0402 
5% 
U109 
2N7002LT1G
G
D S
R1027 100 
1% R0402 
C771 
10UF 
X6S 
25V 
U95 
2N7002LT1G 
G
D S
U94 
2N7002LT1G 
G
D S
C769 
0.1UF 
X7R 
16V 
CH4103K1B08 
C773 
0.1UF 
X7R 
16V 
C794 100PF
NPO 50V
U100 
ADM1178-2ARMZ-R7 
SENSE 2VCC 1
GATE 9
GND 4 TIMER 5 SCL 6
ON 3
ADR 8 ALERT# 10 
SDA 7
C774 
0.1UF 
X7R 
16V 
CH4103K1B08
R1023 4.7K 
R0402 5% 
R1014 
8.2K 
5% 
R0402 
NI 
C780 
0.047UF 
C0603 
X7R 
10% 
50V 
R1281 33 
R0402 5% 
U98 
2N7002LT1G 
G
D S
C778 
0.1UF 
X7R 
16V 
C0402 
10% 
C772 
0.1UF 
X7R 
16V 
CH4103K1B08 
R1026 
12.4K 
1% 
R0402 
R1021 10 
1% R0402 



5
5
4
4
3
3
2
2
1
1
D D
C C
B B
A A
CPLD1 
SYS_AUTO_POWER_ON_N 
*LOW:SYSTEM AUTO POWER ON AFTER 3 SECOND 
 HIGH: BY USER CONTROL 
SYS_AUTO_POWER_ON_N 
LED_CPU_NODE1_CPLD 
TP_CPLD_NODE1_IO39 
JTAG_CPLD1_TDO 
TP_FM_CPLD_NODE1_BMC_EXTRST_L 
FM_CPLD_NODE1_BMC_SRST_L FM_BMC_NODE1_RESET_L 
TP_FM_CPLD_NODE1_SSI_PERST_L 
TP_FM_CPLD_NODE1_PWR_BTN_BMC 
TP_FM_CPLD_NODE1_P3V3_STB_SW_EN 
TP_FM_CPLD_NODE1_P1V0_STB_EN 
LED_PWR_NODE1_L 
LED_CPU_NODE1_CPLD LED_CPU_NODE1_CPLD_D 
JTAG_CPLD1_TCK 
JTAG_CPLD1_TDO 
JTAG_CPLD1_TMS 
JTAG_CPLD1_TDI 
JTAG_CPLD1_TCK 
JTAG_CPLD1_TMS 
JTAG_CPLD1_TCK 
JTAG_CPLD1_TMS 
JTAG_CPLD1_TDI 
JTAG_CPLD1_TDI 
CPLD1_RSV1 
CPLD1_RSV2 
CPLD1_RSV3 
CPLD1_RSV3 
CPLD1_RSV1 
CPLD1_RSV2 
SYS_AUTO_POWER_ON_N 
PWRGD_NODE1_P5V_STB_PG_CPLD 
PWRGD_NODE1_P5V_STB_PG_CPLD 
PWRGD_NODE1_P3V3_STB_PG_CPLD 
PWRGD_NODE1_P3V3_STB_PG_CPLD 
JTAG_CPLD1_TMS 
JTAG_CPLD1_TCK 
JTAG_CPLD1_TDI 
JTAG_CPLD1_TDO 
FM_CPU_NODE1_SLPRDY_L (19) 
FM_CPU_NODE1_SLPMODE (19) 
FM_CPLD_NODE1_WDT (68) 
FM_NODE1_CORE0_1_RST_L (68) 
FM_CPLD_NODE1_PWR_BTN_L (69) 
FM_CPLD_NODE1_DEBUG_MODE 
FM_CPU_NODE1_RSTRDY_L (19) 
FM_CPLD_NODE1_JTAG_POK_L (68) 
PWRGD_NODE1_PVCCP_PG (81) 
LED_PWR_NODE1_L (58) 
PWRGD_NODE1_PVTT_DDR_PG (80) 
FM_NODE1_DDR3_DRAM_POK_L (68) 
FM_CPLD_NODE1_CPU_RESET_L (19,29,49,50,52) 
PWRGD_NODE1_P1V05_PG (78) 
PWRGD_NODE1_P3V3_PG (77) 
FM_NODE1_DDR3_SYSPWRGD_L (68) 
PWRGD_NODE1_P1V05_SUS_PG (72) 
FM_CPLD_NODE1_CPU_RSMRST_L (19) 
PWRGD_NODE1_PVDDR_STB_PG (80) 
FM_CPLD_NODE1_SYS_PG (19) 
PWRGD_NODE1_P1V5_SUS_PG (73) 
RST_CPU_NODE1_SRTCRST_L (16) 
FM_CPU_NODE1_RSTWARN (19) 
PWRGD_NODE1_P1V26_BMC_PG (75) 
CLK_33K_CPU_NODE1_SUSCLK (19,68) 
FM_CPLD_NODE1_BMC_PERST_L (32) 
PWRGD_NODE1_P1V538_BMC_PG (74) 
PWRGD_NODE1_P1V8_STB_PG (74) 
FM_BMC_NODE1_RESET_L (35) 
FM_CPLD_NODE1_USB_PERST_L (47) 
FM_CPLD_NODE1_LPCRST_L (23) 
FM_CPLD_NODE1_USB_PONRST_L (47) 
FM_CPLD_NODE1_P1V8_SUS_EN (73) 
FM_CPLD_NODE1_CLK_PG (13) 
FM_CPLD_NODE1_PVCCP_EN (81) 
FM_CPLD_NODE1_PVTT_DDR_EN (80) 
FM_CPLD_NODE1_P1V05_EN (78) 
FM_CPLD_NODE1_P1V0_EN (72) 
FM_CPLD_NODE1_P1V5_EN (79) 
FM_CPLD_NODE1_P1V8_EN (78) 
FM_CPLD_NODE1_P3V3_SUS_EN (76) 
PWRGD_NODE1_P12V_PG (66) 
FM_CPLD_NODE1_P1V05_SUS_EN (72) 
FM_CPLD_NODE1_PVDDR_STB_EN (80) 
FM_CPLD_NODE1_P1V5_SUS_EN (73) 
FM_CPLD_NODE1_P1V26_BMC_EN (75) 
FM_CPLD_NODE1_P1V538_BMC_EN (74) 
FM_CPLD_NODE1_P1V8_STB_EN (74) 
FM_CPLD_NODE1_P3V3_EN (77) 
FM_CPLD_NODE1_P5V_EN (77) 
FM_CPLD_NODE1_PWR_BTN_CPU (16) 
FM_CPLD_NODE1_SATA_PERST_L (45) 
IRQ_LVC3_CPU_NODE1_WAKE_L (19,30,32,45,47,49,50) 
CPLD_EXT_RST_N (60) 
RST_BTN_NODE1_L (69) 
H_CPU_NODE1_VR_HOT_L (81) 
CPLD123_RSV1 (52,60) 
CPLD123_RSV2 (52,60) 
CPLD123_RSV3 (52,60) 
CPLD_ROW_LATCH (16) 
CPLD_ROW_EN (16) 
CPLD_CPU_THRMTRIP_N (68) 
CPLD_THRMTRIP_LOG_N 
PWRGD_NODE1_P1V0 (72) 
FM_CPLD_PCIE_SW_PERST_L (30) 
PWRGD_NODE1_P5V_STB_PG (71) 
PWRGD_NODE1_P3V3_STB_PG (71) 
CM_STATUS_LED_N (58) 
SIO_JTAG_CPLD1_TCK 
SIO_JTAG_CPLD1_TMS 
SIO_JTAG_CPLD1_TDO (52) 
SIO_JTAG_CPLD1_TDI 
P3V3_STB_NODE1 
P3V3_STB_NODE1 
P3V3_STB_NODE1 
P3V3_STB_NODE1 
P3V3_STB_NODE1 
P3V3_STB_NODE1 
Title 
Size Document Number Rev
Date: Sheet 
of 
Node1 CPLD 1 1A
Chassis Manager Assembly V1 
Cloud Server Infrastructure Engineering
C
67 85Monday, January 27, 2014 
Title 
Size Document Number Rev
Date: Sheet 
of 
Node1 CPLD 1 1A
Chassis Manager Assembly V1 
Cloud Server Infrastructure Engineering
C
67 85Monday, January 27, 2014 
Title 
Size Document Number Rev
Date: Sheet 
of 
Node1 CPLD 1 1A
Chassis Manager Assembly V1 
Cloud Server Infrastructure Engineering
C
67 85Monday, January 27, 2014 
C786 
1UF 16V 
10% 
C0603 
X7R 
U102 
EPM240F100C5N 
GNDIO_4 D7 GNDIO_5 D5 GNDINT_0 E6 GNDINT_1 F5 
VCCIO2_0 F7 VCCIO2_1 D6 VCCIO2_2 D4 VCCIO1_0 E4 VCCIO1_1 G4 VCCIO1_2 G6 VCCINT_0 F4 VCCINT_1 E7 
IO_79 K8 
IO_78 K7 
IO_77 K6 
IO_76 K5 
IO_75 K4 
IO_74 K3 
IO_73 K2 
IO_72 K10 
IO_71 K1 
IO_70 J9 
IO_69 J8 
DEV_OE_IO_68 J7 
IO_67 J6 
IO_66 J5 
IO_65 J4 
IO_64 J3 
IO_63 J10 
IO_62 H9 
IO_61 H8 
IO_60 H7 
IO_59 H6 
IO_58 H5 
IO_57 H4 
IO_56 H10 
IO_55 H1 
IO_54 G9 
IO_53 G8 
IO_52 G3 
IO_51 G2 
IO_50 G10 
IO_49 G1 
IO_48 F9 
GCLK2_IO_47 F8 
IO_46 F3 
IO_45 F2 
IO_44 F10 
IO_43 F1 
IO_42 E9 
IO_41 E8 
IO_40 E3 
GCLK0_IO_39 E2 
GCLK3_IO_38 E10 
TCK H3 
TDI H2 
TMS J1 
TDO J2 
GCLK1_IO_37 E1 
IO_36 D9 
IO_35 D8 
IO_34 D3 
IO_33 D2 
IO_32 D10 
IO_31 D1 
IO_30 C9 
IO_29 C8 
IO_28 C7 
IO_27 C6 
IO_26 C5 
IO_25 C4 
IO_24 C3 
IO_23 C2 
IO_22 C10 
IO_21 C1 
IO_20 B9 
IO_19 B8 
IO_18 B7 
IO_17 B6 
IO_16 B5 
IO_15 B4 
IO_14 B3 
IO_13 B2 
IO_12 B10 
IO_11 B1 
IO_10 A9 
IO_09 A8 
IO_08 A7 
IO_07 A6 
IO_06 A5 
IO_05 A4 
IO_04 A3 
IO_03 A2 
IO_02 A10 
IO_01 A1 
DEV_CLR_N_IO_0 K9 
GNDIO_3 F6 
GNDIO_2 G7 
GNDIO_1 G5 
GNDIO_0 E5 
C782 
10UF 10V 
20% 
X5R 
C0603 
R661 0
R0402 5% 
NI 
R1285 0
R0402 5% 
C784 
1UF 16V 
10% 
C0603 
X7R 
R1246 0
R0402 5% 
NI 
C788 
1UF 16V 
10% 
C0603 
X7R 
R1286 0
R0402 5% 
R1031 4.7K 
R0402 5% 
NI 
J20 
HEADER2X5 
1 2
3 4
5 6
7
9
8
10 
R1287 0
R0402 5% 
R1033 1K 
1% R0402 
NI 
C787 
1UF 16V 
10% 
C0603 
X7R 
R1032 330 
5% R0402 
R1034 10K 
1% R0402 
C789 
1UF 16V 
10% 
C0603 
X7R 
C791 
1UF 16V 
10% 
C0603 
X7R 
R1247 0
R0402 5% 
R1121 10K NI 
1% R0402 
C792 
1UF 16V 
10% 
C0603 
X7R 
R1120 0
R0402 5% 
C785 
1UF 16V 
10% 
C0603 
X7R 
C783 
10UF 10V 
20% 
X5R 
C0603 
R1272 0
R0402 5% 
R660 0
R0402 5% 
NI 
C790 
1UF 16V 
10% 
C0603 
X7R 
R627 0
R0402 5% 
NI 
R1035 10K NI 
1% R0402 
R1030 0 5% R0402 
D21 
LED YEL/GR 
AC
C793 
1UF 16V 
10% 
C0603 
X7R 



5
5
4
4
3
3
2
2
1
1
D D
C C
B B
A A
FM_CPLD_NODE1_JTAG_POK_L FM_CPLD_NODE1_JTAG_POK_R_L 
FM_CPU_NODE1_JTAG_POK 
FM_NODE1_DDR3_DRAM_POK_L FM_NODE1_DDR3_DRAM_POK_R_L 
PWRGD_NODE1_DDR3_DRAM_POK 
FM_NODE1_DDR3_SYSPWRGD_L FM_NODE1_DDR3_SYSPWRGD_R_L 
PWRGD_NODE1_DDR3_SYSPWRGD 
FM_NODE1_DFX_GPIO_GRP05 FM_NODE1_DFX_GPIO_GRP05_R 
FM_NODE1_CORE0_1_RST_L 
FM_CPLD_NODE1_WDT_R 
CLK_33K_CPU_NODE1_SUSCLK_R CLK_33K_CPU_NODE1_SUSCLK 
FM_OSC_NODE1_OSC_NC 
FM_CPLD_NODE1_JTAG_POK_L (67) 
FM_CPU_NODE1_JTAG_POK (16) 
FM_NODE1_DDR3_DRAM_POK_L (67) 
PWRGD_NODE1_DDR3_DRAM_POK (14) 
FM_NODE1_DDR3_SYSPWRGD_L (67) 
PWRGD_NODE1_DDR3_SYSPWRGD (14) 
FM_NODE1_DFX_GPIO_GRP05 (16) 
FM_NODE1_CORE0_1_RST_L (67) 
FM_CPLD_NODE1_WDT (67) 
FM_CPU_NODE1_OWDTOUT (19) 
CLK_33K_CPU_NODE1_SUSCLK (67) 
CPLD_CPU_THRMTRIP_N (67) 
H_CPU_NODE1_THRMTRIP_L (18) 
P1V05_NODE1 
PV_VDDR_NODE1 
PV_VDDR_NODE1 
P3V3_STB_NODE1 
P3V3_STB_NODE1 
P1V05_NODE1 
P3V3_STB_NODE1 
P3V3_STB_NODE1 
P3V3_STB_NODE1 
P1V05_NODE1 
Title 
Size Document Number Rev
Date: Sheet 
of 
Node1 CPLD 2 1A
Chassis Manager Assembly V1 
Cloud Server Infrastructure Engineering
C
68 85Monday, January 27, 2014 
Title 
Size Document Number Rev
Date: Sheet 
of 
Node1 CPLD 2 1A
Chassis Manager Assembly V1 
Cloud Server Infrastructure Engineering
C
68 85Monday, January 27, 2014 
Title 
Size Document Number Rev
Date: Sheet 
of 
Node1 CPLD 2 1A
Chassis Manager Assembly V1 
Cloud Server Infrastructure Engineering
C
68 85Monday, January 27, 2014 
OSC5 
32.768KHZ 
NC/INH 1 GND 2
OUT 3VDD 4
R1131 
1K 
1% 
R0402 
C795 
0.1UF 
X7R 
16V 
C0402 
10% 
R1046 
1K 
1% 
R0402 
Q41 
PMBT390 
B
EC
R1040 
1K 
1% 
R0402 
R1043 1K 
1% R0402 
Q28 
PMBT390 
B
EC
Q26 
PMBT390 
B
EC
R1050 1K 
1% R0402 
R1052 33 
R0402 1% 
R1047 1K 
1% R0402 
Q27 
PMBT390 
B
EC
Q24 
PMBT390 
B
EC
Q25 
PMBT390 
B
EC
R1049 
1K 
1% 
R0402 
R1041 
1K 
1% 
R0402 
R1044 
1K 
1% 
R0402 
R1051 10K 
R0402 1% 
R1042 1K 
1% R0402 
R93 0 R0402 5% 
R1045 1K 
1% R0402 
R1122 1K 
1% R0402 



5
5
4
4
3
3
2
2
1
1
D D
C C
B B
A A
Power Button
RESET BUTTON
RST_BTN_L RST_BTN_NODE1_C_L 
PWR_BTN_NODE1_C_L 
PWR_BTN_NODE1_L 
RST_BTN_NODE1_L (67) 
FM_CPLD_NODE1_PWR_BTN_L (67) 
P3V3_STB_NODE1 
P3V3_STB_NODE1 
P3V3_STB_NODE1 
P3V3_STB_NODE1 
P3V3_STB_NODE1 
P3V3_STB_NODE1 
Title 
Size Document Number Rev
Date: Sheet 
of 
Node1 Power Button 1A
Chassis Manager Assembly V1 
Cloud Server Infrastructure Engineering
C
69 85Monday, January 27, 2014 
Title 
Size Document Number Rev
Date: Sheet 
of 
Node1 Power Button 1A
Chassis Manager Assembly V1 
Cloud Server Infrastructure Engineering
C
69 85Monday, January 27, 2014 
Title 
Size Document Number Rev
Date: Sheet 
of 
Node1 Power Button 1A
Chassis Manager Assembly V1 
Cloud Server Infrastructure Engineering
C
69 85Monday, January 27, 2014 
R1067 0
R0402 5% 
NI 
R1053 
4.7K R0402 
5% 
S3 
STS-02 
1
2
3
4
C565 
0.1UF 
16V 
C0402 
C801 
0.1UF 
  
X7R 
C0402 
10% 
16V 
S1 
STS-02 
1
2
3
4
C802 
1UF 
X7R 
C0805_H61 
10% 
25V 
R1066 0
R0402 5% 
NI 
C799 
0.1UF 
16V 
C0402 
U58 
74LVC1G17GV 
VCC 5
A2
GND 3
Y 4
NC 1
R1063 200 
R0402 1% 
C798 
1UF 
X7R 
C0805_H61 
10% 
25V 
U106 
74LVC1G17GV 
VCC 5
A2
GND 3
Y 4
NC 1
R1054 200 
R0402 1% 
R1062 
4.7K 
R0402 
5% 
C797 
0.1UF 
  
X7R 
C0402 
10% 
16V 



5
5
4
4
3
3
2
2
1
1
D D
C C
B B
A A
POWER_SW1_PWR_CTR_N 
HIGH: RELAY ON(Normal) 
LOW :RELAY OFF 
POWER_SW1_PWR_CTR_N 
HIGH: RELAY ON(Normal) 
LOW :RELAY OFF 
POWER_SW1_PWR_CTR_N 
HIGH: RELAY ON(Normal) 
LOW :RELAY OFF 
POWER_SW1_PWR_CTR_12V 
POWER_SW2_PWR_CTR_12V 
POWER_SW3_PWR_CTR_12V 
POWER_SW1_PWR_CTR_N 
POWER_SW2_PWR_CTR_N 
POWER_SW3_PWR_CTR_N 
POWER_SW1_PWR_CTR_12V_R (61) 
POWER_SW2_PWR_CTR_12V_R (61) 
POWER_SW3_PWR_CTR_12V_R (61) 
P3V3_STB_NODE1 
P3V3_STB_NODE1 
P3V3_STB_NODE1 
P3V3_STB_NODE1 
P12V_AUX 
P12V_AUX 
P3V3_STB_NODE1 
P3V3_STB_NODE1 
P12V_AUX 
Title 
Size Document Number Rev
Date: Sheet 
of 
Level Shift 1A
Chassis Manager Assembly V1 
Cloud Server Infrastructure Engineering
C
70 85Monday, January 27, 2014 
Title 
Size Document Number Rev
Date: Sheet 
of 
Level Shift 1A
Chassis Manager Assembly V1 
Cloud Server Infrastructure Engineering
C
70 85Monday, January 27, 2014 
Title 
Size Document Number Rev
Date: Sheet 
of 
Level Shift 1A
Chassis Manager Assembly V1 
Cloud Server Infrastructure Engineering
C
70 85Monday, January 27, 2014 
Q45 
PBSS5140T 
2 3
1
U108 
2N7002LT1G 
G
D S
R1312 100 
R1003 
10K 
R0402 
1% 
R1129 0
5% R0805 
R1250 2K 
R0402 5% 
C887 
1UF 
16V 
10% 
C0603 
X7R 
NI 
R1292 100 
R1313 100 
R657 
10K 
R0402 
1% 
Q46 
PBSS5140T 
2 3
1
R1072 100 
R1314 100 
R655 
10K 
R0402 
1% 
R1271 100 
R1039 
10K 
R0402 
1% 
R1315 100 
R1130 0
5% R0805 
U104 
2N7002LT1G 
G
D S
C594 10PF 
C0G 50V 
R1316 100 
R1317 100 
R1293 100 
R1038 
10K 
R0402 
1% 
R801 
100K 
R0402 
5% 
R1004 
10K 
R0402 
1% 
R1294 100 
R1059 
10K 
R0402 
1% 
R1318 100 
R802 
10K 
R0402 
1% 
R800 
10K 
R0402 
1% 
C886 
1UF 
16V 
10% 
C0603 
X7R 
NI 
R1319 100 
U105 
2N7002LT1G 
G
D S
C592 10PF 
C0G 50V 
C596 10PF 
C0G 50V 
C934 
1UF 
16V 
10% 
C0603 
X7R 
NI 
U110 
2N7002LT1G 
G
D S
R1295 100 
U107 
2N7002LT1G 
G
D S
R1320 100 
R1128 2K 
R0402 5% 
R1296 100 
R1127 2K 
R0402 5% 
R1060 
100K 
R0402 
5% 
R1073 100 
R803 
100K 
R0402 
5% 
R1249 0
5% R0805 
R1321 100 
Q44 
PBSS5140T 
2 3
1
U111 
2N7002LT1G 
G
D S



5
5
4
4
3
3
2
2
1
1
D D
C C
B B
A A
Design specification 
2012.05.7 Modified by <name> 
Output Voltage = 5V¡Ó5%(DC¡Ó1.5%) 
Output Ripple & Noise < 50mV 
Transient Tolerance = 500mV 
TDC =0.85 A 
Max current = 0.95A 
Over-Current Protection(IC Default*1.3) = 1.248A 
Current Step = 0.95A 
Slew Rate = 0.5A/us 
Work frequency = 700kHZ 
Efficiency > 80% @TDC 
VFB=0.765V 
Rb 
Ra 
SMD 6.86 x 6.47 x 3.0 
DCR=37mohm 
Irms = 5.5A 
Vo=(0.763+0.0017*Vo)*(1+Ra/Rb) = 4.995V 
SMD 6.86 x 6.47 x 3.0 
DCR=30mohm 
Irms = 6A 
Design specification 
2012.5.7 Modified by <name> 
Output Voltage = 3.3V¡Ó5%(DC¡Ó2%) 
Output Ripple & Noise < 50mV 
Transient Tolerance = 330mV 
TDC = 0.4A 
Max current = 0.5A  (bodget=0.45A) 
Over-Current Protection(IC Default*1.3) 
=0.65A 
Current Step = 0.25A 
Slew Rate = 0.5A/us 
Work frequency = 700kHZ 
Efficiency > 80% @TDC 
VFB=0.765V 
Rb 
Ra 
Vo=(0.763+0.0017*Vo)*(1+Ra/Rb) = 3.314V 
P5V_STB_NODE1_EN_P 
SW_P5V_STB_NODE1_BT 
P5V_STB_NODE1_FB 
P5V_STB_NODE1_SS 
SW_P5V_STB_NODE1_PH 
PWRGD_NODE1_P3V3_STB_PG 
P3V3_STB_NODE1_EN 
SW_P3V3_STB_NODE1_BT 
P3V3_STB_NODE1_FB 
P3V3_STB_NODE1_SS 
SW_P3V3_STB_NODE1_PH 
P5V_STB_NODE1_EN 
PWRGD_NODE1_P5V_STB_PG 
PWRGD_NODE1_P5V_STB_PG 
PWRGD_NODE1_P3V3_STB_PG (67) 
PWRGD_NODE1_P5V_STB_PG (67) 
P5V_STB_NODE1 
P12V_AUX 
P5V_STB_NODE1_VREG5 
P5V_STB_NODE1_VREG5 
P12V_AUX 
P3V3_STB_NODE1 
P12V_AUX P3V3_STB_NODE1_VREG5 
P3V3_STB_NODE1_VREG5 
P5V_STB_NODE1 
Title 
Size Document Number Rev
Date: Sheet 
of 
P5V_STB & P3V3_STB 1A
Chassis Manager Assembly V1 
Cloud Server Infrastructure Engineering
C
71 85Monday, January 27, 2014 
Title 
Size Document Number Rev
Date: Sheet 
of 
P5V_STB & P3V3_STB 1A
Chassis Manager Assembly V1 
Cloud Server Infrastructure Engineering
C
71 85Monday, January 27, 2014 
Title 
Size Document Number Rev
Date: Sheet 
of 
P5V_STB & P3V3_STB 1A
Chassis Manager Assembly V1 
Cloud Server Infrastructure Engineering
C
71 85Monday, January 27, 2014 
PC26 
0.1UF 
X7R 
16V 
C0402 
10% 
PC8 
1UF C0402 
X5R 
10V 
10% 
PC25 
0.1UF 
X7R 
16V 
C0402 
10% 
PC21 47PF 
NPO 50V 
C0402 
  
5% 
PC20 
3300PF 
C0402 
X7R 
50V 
10% 
PJ2 
SHORT 
NI 
11 2 2
PC14 
0.1UF 
X7R 
16V 
C0402 
10% 
PC10 47PF 
NPO 50V 
C0402 5% 
PR2 
200K 
R0402 
5% 
R1082 
390K R0402 
5% 
PC1 
10UF 
X6S 
25V 
C1206_H76 
20% 
PR7 73.2K 
1% R0402 
PR1 
100K 
R0402 
5% PC2 
0.1UF 
X7R 
16V 
C0402 
10% 
PC6 
22UF 
X5R 
6.3V 
C0805_H61 
20% 
PR3 121K 
1% R0402 
PC? 
10UF 
6.3V 
C0805_H64 
X5R 
20% 
PC4 
0.1UF X7R 
16V C0402 
10% 
PC? 
10UF 
6.3V 
C0805_H64 
X5R 
20% 
PC18 
0.1UF 
X7R 
16V 
C0402 
10% 
PC19 
1UF C0402 
X5R 
10V 
10% 
PC9 
3300PF 
C0402 
X7R 
50V 
10% 
PL12 
4.7U 
21
PC16 
10UF 
X5R 
6.3V 
C0805_H64 
20% 
PC15 
0.1UF X7R 
16V 
C0402 
10% 
PC11 
10UF 
X6S 
25V 
C1206_H76 
20% 
PL2 
3.3UH 
21
R1103 
1K 
1% 
R0402 
NI 
PC3 
10UF 
X6S 
25V 
C1206_H76 
20% 
R1083 
100K 
5% 
R0402 
PJ1 
SHORT 
NI 
11 2 2
PC17 
22UF 
X5R 
6.3V 
C0805_H61 
20% 
PU1 
TPS54326RGTR 
EN 6
VIN_1 13 
GND 4
PGND_1 7
PG 5
VFB 1
SW_1 9
VBST 12 
GND-EP TH 
VIN_2 14 
VCC 15 
PGND_2 8
VREG5 2
SS 3
SW_2 10 
SW_3 11 
VO 16 
PC5 
10UF 
X5R 
6.3V 
C0805_H64 
20% PR4 
22.1K 
1% 
R0402 
PR8 
22.1K 
1% 
R0402 
PR5 
100K 
R0402 
5% 
PC12 
0.1UF 
X7R 
16V 
C0402 
10% 
PR6 
200K 
R0402 
5% 
PC13 
10UF 
X6S 
25V 
C1206_H76 
20% 
PC7 
0.1UF 
X7R 
16V 
C0402 
10% 
PU2 
TPS54326RGTR 
EN 6
VIN_1 13 
GND 4
PGND_1 7
PG 5
VFB 1
SW_1 9
VBST 12 
GND-EP TH 
VIN_2 14 
VCC 15 
PGND_2 8
VREG5 2
SS 3
SW_2 10 
SW_3 11 
VO 16 



5
5
4
4
3
3
2
2
1
1
D D
C C
B B
A A
Ra 
Rb 
Output Voltage=1.05V+/-1.0% 
PD=(1.8V-1.05V)*0.0003A=0.000225W 
SLEW RATE=2.5A/US 
AC TRANSIENT=+/-4.0% 
MAX CURRENT=0.84A 
Design specification 
TDC=0.84A 
CURRENT STEP=0.42A 
VOUT=0.8*(1+Ra/Rb)=1.05V 
Ra 
Rb 
VOUT=0.8*(1+Ra/Rb)=1.0V 
P1V05_SUS_NODE1_ADJ_S 
P1V05_SUS_NODE1_ADJ 
PWRGD_NODE1_P1V05_SUS_PG 
P1V0_ADJ 
P1V0_ADJ_S 
PWRGD_NODE1_P1V05_SUS_PG (67) 
FM_CPLD_NODE1_P1V05_SUS_EN (67) 
FM_CPLD_NODE1_P1V0_EN (67) 
PWRGD_NODE1_P1V0 (67) 
P1V8_STB_NODE1 P5V_STB_NODE1 
P1V05_SUS_NODE1 
P3V3_STB_NODE1 
P1V8_NODE1 
P1V0_NODE1 
P5V_STB_NODE1 
P3V3_STB_NODE1 
Title 
Size Document Number Rev
Date: Sheet 
of 
P1V05_SUS & P1V0_PLX 1A
Chassis Manager Assembly V1 
Cloud Server Infrastructure Engineering
C
72 85Monday, January 27, 2014 
Title 
Size Document Number Rev
Date: Sheet 
of 
P1V05_SUS & P1V0_PLX 1A
Chassis Manager Assembly V1 
Cloud Server Infrastructure Engineering
C
72 85Monday, January 27, 2014 
Title 
Size Document Number Rev
Date: Sheet 
of 
P1V05_SUS & P1V0_PLX 1A
Chassis Manager Assembly V1 
Cloud Server Infrastructure Engineering
C
72 85Monday, January 27, 2014 
C884 
0.01UF 
16V 
10% 
C0402 
X7R 
NI 
PR10 
9.31K 
1% 
R0402 
U119 
RT9059GQW 
PGOOD 5
EN 6
ADJ 4
VOUT1 1
VIN1 7VDD 10 
EP TH 
VOUT2 2
VOUT3 3
VIN2 8
VIN3 9
C815 1200PF 
50V 
10% X7R 
C0402 
NI 
PC28 
10UF 
X5R 
6.3V 
C0805_H64 
20% 
C810 
10UF 
X5R 
6.3V 
C0805_H64 
PR9 2.37K 
1% R0402 
C816 
0.01UF 
16V 
10% 
C0402 
X7R 
NI 
J21 
SHORT 
NI 
1 122
C852 
0.1UF 
X7R 
16V 
C0402 
10% 
PC27 
10UF 
X5R 
6.3V 
C0805_H64 
20% 
R1084 
4.7K 
5% 
R0402 
C851 1200PF 
50V 
10% X7R 
C0402 
NI 
R1104 
1K 
1% 
R0402 
NI 
C883 
1UF 
X5R 
6.3V 
C0402 
10% 
C809 
1UF 
X5R 
6.3V 
C0402 
10% 
R1086 
9.31K 
1% 
R0402 
R1218 
4.7K 
5% 
R0402 
PJ3 
SHORT 
NI 
11 2 2
J28 
SHORT 
NI 
1 122
PC29 
0.1UF 
X7R 
16V 
C0402 
10% 
C813 
10UF 
6.3V 
X5R 
C0805_H64 
20% 
C812 
10UF 
6.3V 
X5R 
C0805_H64 
20% 
R1105 
1K 
1% 
R0402 
NI 
C814 
0.1UF 
X7R 
16V 
C0402 
10% 
PC22 
10UF 
X5R 
6.3V 
C0805_H64 
20% 
C811 
0.1UF 
X7R 
16V 
C0402 
10% R1085 2.94K 
1% R0402 
U130 
RT9059GQW 
PGOOD 5
EN 6
ADJ 4
VOUT1 1
VIN1 7VDD 10 
EP TH 
VOUT2 2
VOUT3 3
VIN2 8
VIN3 9



5
5
4
4
3
3
2
2
1
1
D D
C C
B B
A A
Ra 
Rb 
VOUT=0.8*(1+Ra/Rb)=1.5V 
Output Voltage=1.5V+/-1.0% 
PD=(1.8V-1.5V)*0.189A=0.0567W 
SLEW RATE=2.5A/US 
AC TRANSIENT=+/-4.0% 
MAX CURRENT=0.84A 
Design specification 
TDC=0.84A 
CURRENT STEP=0.42A 
Vds = 30V 
Id = 40A (at Vgs=10V) 
Rds(on)<6m ohm (at Vgs=10V) 
Rds(on)<7.8m ohm(at Vgs=4.5V) For system, 0.7mA 
P1V5_SUS_NODE1_ADJ 
FM_CPLD_NODE1_P1V8_SUS_EN_LV 
FM_CPLD_NODE1_P1V8_SUS_EN_G 
PWRGD_NODE1_P1V5_SUS_PG (67) 
FM_CPLD_NODE1_P1V5_SUS_EN (67) 
FM_CPLD_NODE1_P1V8_SUS_EN (67) 
P1V8_STB_NODE1 P5V_STB_NODE1 
P1V5_SUS_NODE1 
P3V3_STB_NODE1 
P3V3_STB_NODE1 
P3V3_STB_NODE1 
P5V_STB_NODE1 
P1V8_SUS_NODE1 
P1V8_STB_NODE1 
Title 
Size Document Number Rev
Date: Sheet 
of 
P1V5_SUS & P1V8_SUS 1A
Chassis Manager Assembly V1 
Cloud Server Infrastructure Engineering
C
73 85Monday, January 27, 2014 
Title 
Size Document Number Rev
Date: Sheet 
of 
P1V5_SUS & P1V8_SUS 1A
Chassis Manager Assembly V1 
Cloud Server Infrastructure Engineering
C
73 85Monday, January 27, 2014 
Title 
Size Document Number Rev
Date: Sheet 
of 
P1V5_SUS & P1V8_SUS 1A
Chassis Manager Assembly V1 
Cloud Server Infrastructure Engineering
C
73 85Monday, January 27, 2014 
C818 
10UF 
X5R 
6.3V 
C0805_H64 
C824 
0.01UF 
16V 
10% 
C0402 
X7R 
NI 
R1093 
1K 
1% 
R0402 
Q29 
AON7212 
3
5 2
4
1
C821 
10UF 
6.3V 
X5R 
C0805_H64 
20% 
R1089 
3.3K 
1% 
R0402 
R1087 
4.7K 
5% 
R0402 
R1088 2.94K 
1% R0402 
R1091 
4.02K 
1% 
R0402 
C822 
0.1UF 
X7R 
16V 
C0402 
10% 
R1090 
10K R0402 
1% 
C826 
0.1UF 
X7R 
16V 
C0402 
10% 
C820 
10UF 
6.3V 
X5R 
C0805_H64 
20% 
R1106 
1K 
1% 
R0402 
NI 
U120 
RT9059GQW 
PGOOD 5
EN 6
ADJ 4
VOUT1 1
VIN1 7VDD 10 
EP TH 
VOUT2 2
VOUT3 3
VIN2 8
VIN3 9
R1092 4.02K 
1% R0402 
Q30 
2N7002A-7 
G G
D D
SS
C823 1200PF 
50V 
10% X7R 
C0402 
NI 
C825 0.47UF 
10V 10% 
C0603 X7R 
R1231 
1K 
1% 
R0402 
NI 
C817 
1UF 
X5R 
6.3V 
C0402 
10% 
C819 
0.1UF 
X7R 
16V 
C0402 
10% 



5
5
4
4
3
3
2
2
1
1
D D
C C
B B
A A
Rb 
Ra 
SMD 6.86 x 6.47 x 3.0 
DCR=30mohm 
Irms = 6A 
2012.5.7 Modified by <name> 
Output Voltage = 1.8V¡Ó2% (DC=¡Ó2%) 
Output Ripple & Noise = <18 mV 
Transient Tolerance = 108mV(¡Ó3%) 
TDC = 2A 
Max current =2.4 A 
Over-Current Protection(Max Current*1.3) = 0.91A 
Current Step = 0.3A 
Slew Rate = 2.5A/us 
Work frequency = 700kHZ 
Efficiency > 80% @TDC 
Design specification 
Vo=0.765(1+Ra/Rb) = 1.807V 
VFB=0.765V 
VOUT=0.8*(1+Ra/Rb)=1.530V 
Output Voltage=1.53V+/-1.0% 
PD=(1.8V-1.538V)*0.44A=0.119W 
SLEW RATE=2.5A/US 
AC TRANSIENT=+/-4.0% 
MAX CURRENT=0.84A 
Design specification 
TDC=0.44A 
CURRENT STEP=0.832A 
Ra 
Rb 
P1V8_STB_NODE1_SS 
SW_P1V8_STB_NODE1_PH 
PWRGD_NODE1_P1V8_STB_PG 
FM_CPLD_NODE1_P1V8_STB_S_EN 
SW_P1V8_STB_NODE1_BT 
P1V8_STB_NODE1_FB 
P1V538_BMC_NODE1_ADJ 
PWRGD_NODE1_P1V538_BMC_PG 
P1V538_STB_NODE1_ADJ_S 
FM_CPLD_NODE1_P1V8_STB_EN (67) 
PWRGD_NODE1_P1V8_STB_PG (67) 
PWRGD_NODE1_P1V538_BMC_PG (67) 
FM_CPLD_NODE1_P1V538_BMC_EN (67) 
P12V_AUX 
P1V8_STB_NODE1 
P1V8_STB_NODE1_VREG5 
P1V8_STB_NODE1_VREG5 
P5V_STB_NODE1 
P1V8_NODE1 P5V_STB_NODE1 
P1V538_BMC_NODE1 
P3V3_STB_NODE1 
Title 
Size Document Number Rev
Date: Sheet 
of 
P1V8_STB & P1V538_STB 1A
Chassis Manager Assembly V1 
Cloud Server Infrastructure Engineering
C
74 85Monday, January 27, 2014 
Title 
Size Document Number Rev
Date: Sheet 
of 
P1V8_STB & P1V538_STB 1A
Chassis Manager Assembly V1 
Cloud Server Infrastructure Engineering
C
74 85Monday, January 27, 2014 
Title 
Size Document Number Rev
Date: Sheet 
of 
P1V8_STB & P1V538_STB 1A
Chassis Manager Assembly V1 
Cloud Server Infrastructure Engineering
C
74 85Monday, January 27, 2014 
R1095 9.31K 
1% R0402 
NI 
PC35 
0.1UF 
X7R 
16V 
C0402 
10% 
PR17 
10.2K 
1% 
R0402 
NI 
PC34 
10UF 
X6S 
25V 
C1206_H76 
20% 
PC130 
10UF 
X5R 
6.3V 
C0805_H64 
20% 
C828 
10UF 
X5R 
6.3V 
C0805_H64 
NI 
C830 
10UF 
6.3V 
X5R 
C0805_H64 
20% 
NI 
C832 
0.1UF 
X7R 
16V 
C0402 
10% 
NI 
R1232 
1K 
1% 
R0402 
NI 
PC41 
3300PF 
C0402 
X7R 
50V 
10% 
PC32 
10UF 
X6S 
25V 
C1206_H76 
20% 
PC37 
10UF 
X5R 
6.3V 
C0805_H64 
20% 
J22 
SHORT 
NI 
11 2 2
C827 
1UF 
X5R 
6.3V 
C0402 
10% 
NI 
PL4 
3.3UH 
21
C834 
0.01UF 
16V 
10% 
C0402 
X7R 
NI 
R1233 
1K 
1% 
R0402 
NI 
C831 
10UF 
6.3V 
X5R 
C0805_H64 
20% 
NI 
PR14 
200K 
R0402 
5% 
PC40 
1UF C0402 
X5R 
10V 
10% 
PU4 
TPS54326RGTR 
EN 6
VIN_1 13 
GND 4
PGND_1 7
PG 5
VFB 1
SW_1 9
VBST 12 
GND-EP TH 
VIN_2 14 
VCC 15 
PGND_2 8
VREG5 2
SS 3
SW_2 10 
SW_3 11 
VO 16 
C833 1200PF 
50V 
10% X7R 
C0402 
NI 
PC36 
0.1UF 
X7R 
16V 
C0402 
10% 
PJ4 
SHORT 
NI 
11 2 2
PC42 22PF 
NPO 50V 
C0402 
  
5% 
PR15 30.1K 
1% R0402 
R1094 
4.7K 
5% 
R0402 
NI 
PC39 
0.1UF 
X7R 
16V 
C0402 
10% 
PR13 
100K 
R0402 
5% 
PC33 
0.1UF 
X7R 
16V 
C0402 
10% 
U121 
RT9059GQW 
NI 
PGOOD 5
EN 6
ADJ 4
VOUT1 1
VIN1 7VDD 10 
EP TH 
VOUT2 2
VOUT3 3
VIN2 8
VIN3 9
PC38 
22UF 
X5R 
6.3V 
C0805_H61 
20% 
PC30 
0.1UF 
X7R 
16V 
C0402 
10% 
PR16 
22.1K 
1% 
R0402 
C829 
0.1UF 
X7R 
16V 
C0402 
10% 
NI 



5
5
4
4
3
3
2
2
1
1
D D
C C
B B
A A
Output Voltage=1.26V+/-1.0% 
PD=(1.8V-1.26V)*0.84A=0.45W 
SLEW RATE=2.5A/US 
AC TRANSIENT=+/-4.0% 
MAX CURRENT=0.84A 
Design specification 
TDC=0.84A 
CURRENT STEP=0.42A 
Vnom=0.8(1+Ra/Rb)=1.2608 
Ra 
Rb 
P1V26_BMC_NODE1_ADJ 
P1V26_STB_NODE1_ADJ_S 
FM_CPLD_NODE1_P1V26_BMC_EN (67) 
PWRGD_NODE1_P1V26_BMC_PG (67) 
P1V8_NODE1 
P1V26_BMC_NODE1 
P5V_STB_NODE1 
P3V3_STB_NODE1 
Title 
Size Document Number Rev
Date: Sheet 
of 
P1V26_STB 1A
Chassis Manager Assembly V1 
Cloud Server Infrastructure Engineering
C
75 85Monday, January 27, 2014 
Title 
Size Document Number Rev
Date: Sheet 
of 
P1V26_STB 1A
Chassis Manager Assembly V1 
Cloud Server Infrastructure Engineering
C
75 85Monday, January 27, 2014 
Title 
Size Document Number Rev
Date: Sheet 
of 
P1V26_STB 1A
Chassis Manager Assembly V1 
Cloud Server Infrastructure Engineering
C
75 85Monday, January 27, 2014 
C839 
1UF 
X5R 
6.3V 
C0402 
NI 
R1234 
1K 
1% 
R0402 
NI 
R1097 
576 
1% 
R0402 
NI 
C838 
10UF 
X5R 
6.3V 
C0805_H64 
NI 
C836 
10UF 
X5R 
6.3V 
C0805_H64 
NI 
C840 
0.1UF 
X7R 
16V 
C0402 
NI 
J23 
SHORT 
NI 
1 122C837 
0.1UF 
X7R 
16V 
C0402 
10% 
NI 
C835 
1UF 
X5R 
6.3V 
C0402 
NI 
R1098 
1K 
1% 
R0402 
NI 
U122 
RT9059GQW 
NI 
PGOOD 5
EN 6
ADJ 4
VOUT1 1
VIN1 7VDD 10 
EP TH 
VOUT2 2
VOUT3 3
VIN2 8
VIN3 9
R1096 
4.7K 
R0402 
5% NI 



5
5
4
4
3
3
2
2
1
1
D D
C C
B B
A A
For system, 0.4mA 
Vds = 30V 
Id = 40A (at Vgs=10V) 
Rds(on)<6m ohm (at Vgs=10V) 
Rds(on)<7.8m ohm(at Vgs=4.5V) 
FM_CPLD_NODE1_P3V3_SUS_EN_LV 
FM_CPLD_NODE1_P3V3_SUS_EN_G 
FM_CPLD_NODE1_P3V3_SUS_EN (67) 
P3V3_STB_NODE1 
P3V3_STB_NODE1 
P12V_AUX P3V3_STB_NODE1 
P3V3_SUS_NODE1 
Title 
Size Document Number Rev
Date: Sheet 
of 
P3V3_SUS & P3V3_STB_SW 1A
Chassis Manager Assembly V1 
Cloud Server Infrastructure Engineering
C
76 85Monday, January 27, 2014 
Title 
Size Document Number Rev
Date: Sheet 
of 
P3V3_SUS & P3V3_STB_SW 1A
Chassis Manager Assembly V1 
Cloud Server Infrastructure Engineering
C
76 85Monday, January 27, 2014 
Title 
Size Document Number Rev
Date: Sheet 
of 
P3V3_SUS & P3V3_STB_SW 1A
Chassis Manager Assembly V1 
Cloud Server Infrastructure Engineering
C
76 85Monday, January 27, 2014 
R1102 
1K 
1% 
R0402 
Q31 
AON7212 
3
5 2
4
1
R1099 
10K R0402 
1% 
C841 0.047UF 
50V 10% 
C0603 X7R 
Q32 
2N7002A-7 
G G
D D
SS
C842 
0.1UF 
X7R 
16V 
C0402 
10% 
R1101 4.02K 
1% R0402 
R1235 
1K 
1% 
R0402 
NI 
R1100 
4.02K 
1% 
R0402 



5
5
4
4
3
3
2
2
1
1
D D
C C
B B
A A
For system, 0.7A 
Vds = 30V 
Id = 40A (at Vgs=10V) 
Rds(on)<6m ohm (at Vgs=10V) 
Rds(on)<7.8m ohm(at Vgs=4.5V) 
SMD 6.86 x 6.47 x 3.0 
DCR=30mohm 
Irms = 6A 
VFB=0.765V 
Rb 
Ra 
Vo=(0.763+0.0017*Vo)*(1+Ra/Rb) = 3.314V 
2012.5.7 Modified by <name> 
Design specification 
Output Voltage = 3.3V¡Ó5%(DC¡Ó2%) 
Output Ripple & Noise < 50mV 
Transient Tolerance = 330mV 
TDC =1.6A 
Max current = 2A (bodget 1.914A) 
Over-Current Protection(IC Default*1.3) =2.6 A 
Current Step = 0.5A 
Slew Rate = 1A/us 
Work frequency = 700kHZ 
Efficiency > 80% @TDC 
FM_CPLD_NODE1_P5V_EN_LV 
FM_CPLD_NODE1_P5V_NODE1_EN_G 
FM_CPLD_NODE1_P3V3_S_EN 
SW_P3V3_NODE1_BT 
P3V3_NODE1_SS 
P3V3_NODE1_FB 
SW_P3V3_NODE1_PH 
PWRGD_NODE1_P3V3_PG 
FM_CPLD_NODE1_P5V_EN (67) 
FM_CPLD_NODE1_P3V3_EN (67) 
PWRGD_NODE1_P3V3_PG (67) 
P5V_NODE1 
P3V3_STB_NODE1 
P3V3_STB_NODE1 
P12V_AUX P5V_STB_NODE1 
P3V3_NODE1 
P3V3_NODE1_VREG5 
P3V3_NODE1_VREG5 P12V_AUX 
P5V_STB_NODE1 
Title 
Size Document Number Rev
Date: Sheet 
of 
P5V & P3V3 1A
Chassis Manager Assembly V1 
Cloud Server Infrastructure Engineering
C
77 85Monday, January 27, 2014 
Title 
Size Document Number Rev
Date: Sheet 
of 
P5V & P3V3 1A
Chassis Manager Assembly V1 
Cloud Server Infrastructure Engineering
C
77 85Monday, January 27, 2014 
Title 
Size Document Number Rev
Date: Sheet 
of 
P5V & P3V3 1A
Chassis Manager Assembly V1 
Cloud Server Infrastructure Engineering
C
77 85Monday, January 27, 2014 
PL17 
3.3UH 
21C933 
0.1UF 
X7R 
16V 
C0402 
10% PC52 
3300PF 
C0402 
X7R 
50V 
10% 
PC53 47PF 
NPO 50V 
C0402 5% 
PC45 
10UF 
X6S 
25V 
C1206_H76 
20% 
R1109 4.02K 
1% R0402 
R1108 
4.02K 
1% 
R0402 
Q36 
2N7002A-7 
G G
D D
SS
PC48 
10UF 
X5R 
6.3V 
C0805_H64 
20% 
PJ5 
SHORT 
NI 
11 2 2
PR18 
100K 
R0402 
5% 
C845 4.7UF 
16V 10% 
C0805_H61 X7R 
PR20 73.2K 
1% R0402 
R1107 
330K R0402 
5% 
PC49 
22UF 
X5R 
6.3V 
C0805_H61 
20% 
PU5 
TPS54326RGTR 
EN 6
VIN_1 13 
GND 4
PGND_1 7
PG 5
VFB 1
SW_1 9
VBST 12 
GND-EP TH 
VIN_2 14 
VCC 15 
PGND_2 8
VREG5 2
SS 3
SW_2 10 
SW_3 11 
VO 16 
R1110 
1K 
1% 
R0402 
PC44 
0.1UF 
X7R 
16V 
C0402 
10% 
PC51 
1UF C0402 
X5R 
10V 
10% 
PR19 
200K 
R0402 
5% 
C846 
0.1UF 
X7R 
16V 
C0402 
10% 
PC46 
0.1UF 
X7R 
16V 
C0402 
10% 
PR21 
22.1K 
1% 
R0402 
PC131 
10UF 
X5R 
6.3V 
C0805_H64 
20% 
R1237 
1K 
1% 
R0402 
NI 
PC43 
10UF 
X6S 
25V 
C1206_H76 
20% 
Q35 
AON7212 
3
5 2
4
1
R1236 
1K 
1% 
R0402 
NI 
PC50 
0.1UF 
X7R 
16V 
C0402 
10% 
PC47 
0.1UF 
X7R 16V 
C0402 
10% 



5
5
4
4
3
3
2
2
1
1
D D
C C
B B
A A
Vds = 30V 
Id = 40A (at Vgs=10V) 
Rds(on)<6m ohm (at Vgs=10V) 
Rds(on)<7.8m ohm(at Vgs=4.5V) 
For system, 0.23A 
FDML7610AS 
VGS=4.5V(H/S=12M/LS=5.5M) 
Q1(rds type)=8.5mohm 
Q2(rds type)=4.1mohm 
SMD 6.86 x 6.47 x 3.0 
DCR=15mohm 
Irms = 9A 
Place decvice side 
2012.5.7 Modified by <name> 
Design specification 
Output Voltage = 1.05V¡Ó4.5% (DC=¡Ó1.5%) 
Output Ripple & Noise = <21 mV 
Transient Tolerance = 94.5mV 
TDC = 4.7A 
Max current =5.7 A (bodget 5.545A) 
Over-Current Protection(Max Current*1.3) = 7.41A 
Current Step = 2.4A 
Slew Rate = 15A/us 
Work frequency = 500kHZ 
Efficiency > 80% @TDC 
FM_CPLD_NODE1_P1V8_EN_LV 
FM_CPLD_NODE1_P1V8_EN_G 
SW_P1V05_NODE1_DRVL 
P1V05_NODE1_VREF 
P1V05_NODE1_TRIP 
P1V05_NODE1_COMP 
P1V05_NODE1_EN 
PWRGD_NODE1_P1V05_PG 
SW_P1V05_NODE1_PH 
SW_P1V05_NODE1_BT 
P1V05_NODE1_MODE 
VSENSE_P1V05_NODE1_N 
SW_P1V05_NODE1_PH 
VSENSE_P1V05_NODE1_P 
P1V05_NODE1_VREFIN 
SW_P1V05_NODE1_VIN_FLT 
SW_P1V05_NODE1_DRVH 
P1V05_NODE1_VSNS 
FM_CPLD_NODE1_P1V8_EN (67) 
SW_P1V05_NODE1_PH 
SW_P1V05_NODE1_PH 
PWRGD_NODE1_P1V05_PG (67) 
FM_CPLD_NODE1_P1V05_EN (67) 
P3V3_STB_NODE1 
P3V3_STB_NODE1 
P5V_STB_NODE1 
P1V8_NODE1 
P1V8_STB_NODE1 
P1V05_NODE1 
P12V_AUX 
P3V3_NODE1 
P1V05_NODE1 
P5V_STB_NODE1 
P1V05_NODE1 
P3V3_NODE1 
P3V3_NODE1 
Title 
Size Document Number Rev
Date: Sheet 
of 
P1V8 & P1V05 1A
Chassis Manager Assembly V1 
Cloud Server Infrastructure Engineering
C
78 85Monday, January 27, 2014 
Title 
Size Document Number Rev
Date: Sheet 
of 
P1V8 & P1V05 1A
Chassis Manager Assembly V1 
Cloud Server Infrastructure Engineering
C
78 85Monday, January 27, 2014 
Title 
Size Document Number Rev
Date: Sheet 
of 
P1V8 & P1V05 1A
Chassis Manager Assembly V1 
Cloud Server Infrastructure Engineering
C
78 85Monday, January 27, 2014 
PC54 
1500PF 
X7R 
50V 
C0402 
10% 
PR27 100 
1% R0402 
PC66 
10UF 
X7R 
10V 
C0805_H61 
10% 
NI 
R1112 
4.02K 
1% 
R0402 
C847 1UF 
16V 10% 
C0603 X7R 
C848 
0.1UF 
X7R 
16V 
C0402 
10% 
PC56 
10UF 
X6S 
25V 
C1206_H76 
20% 
+
PC64 
330UF 
TANT 
2V 
35% 
TAJ_SX 
NI 
1 2
PC57 
10UF 
X6S 
25V 
C1206_H76 
20% 
PU6 
TPS51219RTER 
PGOOD 16 
VREF 1
REFIN 2
GSNS 3
VSNS 4
DRVH 11 
TRIP 6
SW 12 
VBST 13 EN 14 
GND_TP TH 
COMP 5
GND 7
PGND 8
DRVL 10 
MODE 15 
V5 9
PC62 
1000PF 
C0402 
16V 
X7R 
NI 
10% 
PR24 4.7K 
R0402 5% 
Q38 
2N7002A-7 
G G
D D
SS
PJ7 NI 
SHORT_R0402 
11 2 2
PL6 
1.5UH 
21
R1114 
1K 
1% 
R0402 
PJ8 NI 
SHORT_R0402 
11 2 2
PC55 
10UF 
X6S 
25V 
C1206_H76 
20% 
PR29 10 
R0402 1% 
PR25 4.7K 
R0402 5% 
R1111 
10K R0402 
1% 
PC60 0.1UF 
X7R 16V C0402 
10% 
PR28 27.4K 
R0402 1% 
R1239 1K 
1% R0402 
NI 
PJ6 
SHORT NI 
11 2 2
PC68 
10UF 
X5R 
6.3V 
C0805_H64 
20% 
R1238 
1K 
1% 
R0402 
NI 
PR26 1K 
R0402 1% 
PC67 
10UF 
X5R 
6.3V 
C0805_H64 
20% 
PC61 
0.1UF 
X7R 
16V 
C0402 
10% 
PC58 
0.1UF 
X7R 
16V 
C0402 
10% 
+
PC63 
330UF 
TANT 
2V 
35% 
TAJ_SX 
1 2
PC65 0.1UF 
C0402 X7R 
16V 10% 
PC69 
0.01UF 
C0402 
16V 
X7R 
10% 
R1113 4.02K 
1% R0402 
PR23 
4.7K 
R0402 
5% 
NI 
PQ1 
FDML7610AS 
3
1
2
D1_EP 
S1/D2_EP 
4
8
5-6-7 
PC70 
1000PF X7R 
50V 
C0402 
5% 
PR30 100 
1% R0402 
Q37 
AON7212 
3
5 2
4
1
PC59 
1UF 
X7R 
16V C0603 
10% 
PR22 0
5% R1206 



5
5
4
4
3
3
2
2
1
1
D D
C C
B B
A A
Vds = 30V 
Id = 40A (at Vgs=10V) 
Rds(on)<6m ohm (at Vgs=10V) 
Rds(on)<7.8m ohm(at Vgs=4.5V) 
For system, 0.16A 
FM_CPLD_NODE1_P1V5_EN_G 
FM_CPLD_NODE1_P1V5_EN_LV 
FM_CPLD_NODE1_P1V5_EN (67) 
P3V3_STB_NODE1 
P3V3_STB_NODE1 
P5V_STB_NODE1 P1V5_SUS_NODE1 
P1V5_NODE1 
Title 
Size Document Number Rev
Date: Sheet 
of 
P1V5 & P1V0 1A
Chassis Manager Assembly V1 
Cloud Server Infrastructure Engineering
C
79 85Monday, January 27, 2014 
Title 
Size Document Number Rev
Date: Sheet 
of 
P1V5 & P1V0 1A
Chassis Manager Assembly V1 
Cloud Server Infrastructure Engineering
C
79 85Monday, January 27, 2014 
Title 
Size Document Number Rev
Date: Sheet 
of 
P1V5 & P1V0 1A
Chassis Manager Assembly V1 
Cloud Server Infrastructure Engineering
C
79 85Monday, January 27, 2014 
Q40 
2N7002A-7 
G G
D D
SS
C850 
0.1UF 
X7R 
16V 
C0402 
10% 
R1116 
4.02K 
1% 
R0402 
C849 1UF 
16V 10% 
C0603 X7R 
R1115 
10K R0402 
1% 
Q39 
AON7212 
3
5 2
4
1
R1118 
1K 
1% 
R0402 
R1240 
1K 
1% 
R0402 
NI 
R1117 4.02K 
1% R0402 



5
5
4
4
3
3
2
2
1
1
D D
C C
B B
A A
Output Voltage = 0.75V or 0.675 ¡Ó5% 
Output Ripple & Noise < 15mV or  13.5mv 
Transient Tolerance = 75mV or 67.5mv 
TDC = 0.4A 
Max current = 0.4A 
PD = (1.5V - 0.75V) ¡Ñ 0.4A = 0.3W 
or 
PD = (1.35V - 0.675V) ¡Ñ 0.4A = 0.27W 
SMD 6.86 x 6.47 x 3.0 
DCR=30mohm 
Irms = 6A 
FDML7610AS 
VGS=4.5V(H/S=12M/LS=5.5M) 
Q1(rds type)=8.5mohm 
Q2(rds type)=4.1mohm 
Place decvice side 
2012.5.7 Modified by <name> 
Design specification 
Output Voltage = 1.5 OR 1.35V¡Ó4% 
(DC=¡Ó1.5%) 
Output Ripple & Noise = <15mV or 13mV 
Transient Tolerance = +/-4% 
TDC =3.6A 
Max current =4.5 A (bodget4.206A) 
Over-Current Protection(Max Current*1.3) = 5.85A 
Current Step = 3A 
Slew Rate = 10A/us 
Work frequency = 350kHZ 
Efficiency > 80% @TDC 
VID 0=LOW   1.5V 
VID 0=HIGH  1.35V 
PWRGD_NODE1_PVTT_DDR_PG 
PV_VTT_DDR_NODE1_REFIN 
PV_VTT_DDR_NODE1_REFOUT 
PV_VTT_DDR_NODE1_VOSNS 
PV_VDDR_NODE1_V1 
PV_VDDR_NODE1_V0 
PV_VDDR_NODE1_VREF 
SW_PV_VDDR_NODE1_DRVL 
SW_PV_VDDR_NODE1_PH 
SW_PV_VDDR_NODE1_BT 
SW_PV_VDDR_NODE1_PH 
SW_PV_VDDR_NODE1_VIN_FLT 
SW_PV_VDDR_NODE1_DRVH 
PV_VDDR_NODE1_VID1 
PV_VDDR_NODE1_SLEW 
PV_VDDR_NODE1_EN 
PV_VDDR_NODE1_TRIP 
VR_NODE1_VDDR_1V5_CNTL 
PV_VDDR_NODE1_VID0 
PV_VDDR_NODE1_MODE 
VSENSE_PV_VDDR_NODE1_P 
VSENSE_PV_VDDR_NODE1_N 
FM_CPLD_NODE1_PVTT_DDR_EN 
PWRGD_NODE1_PVTT_DDR_PG (67) 
FM_CPLD_NODE1_PVTT_DDR_EN (67) 
SW_PV_VDDR_NODE1_PH 
SW_PV_VDDR_NODE1_PH 
FM_CPLD_NODE1_PVDDR_STB_EN (67) 
PWRGD_NODE1_PVDDR_STB_PG (67) 
VR_NODE1_VDDR_1V5_CNTL (16) 
PV_VTT_DDR_NODE1 
P3V3_STB_NODE1 
PV_VDDR_NODE1 
P3V3_STB_NODE1 
PV_VDDR_NODE1 
PV_VDDR_NODE1 
P5V_STB_NODE1 
P12V_AUX 
P3V3_STB_NODE1 
PV_VDDR_NODE1 
Title 
Size Document Number Rev
Date: Sheet 
of 
PV_VDDR & PV_VTT_DDR 1A
Chassis Manager Assembly V1 
Cloud Server Infrastructure Engineering
C
80 85Monday, January 27, 2014 
Title 
Size Document Number Rev
Date: Sheet 
of 
PV_VDDR & PV_VTT_DDR 1A
Chassis Manager Assembly V1 
Cloud Server Infrastructure Engineering
C
80 85Monday, January 27, 2014 
Title 
Size Document Number Rev
Date: Sheet 
of 
PV_VDDR & PV_VTT_DDR 1A
Chassis Manager Assembly V1 
Cloud Server Infrastructure Engineering
C
80 85Monday, January 27, 2014 
C860 
0.1UF 
16V 
C0402 
X7R 
10% 
C857 
10UF 
6.3V 
C0805_H64 
X5R 
20% 
PU7 
TPS51518RUKR 
MODE 16 
GSNS 1
V3 2
V2 3
V1 4
BST 11 
VREF 6
SW 12 
DRVH 13 
DRVL 14 
GND_TP TH 
V0 5
PGOOD 7
VID0 8
EN 10 
V5IN 15 
VID1 9
GND 17 
SLEW 19 
TRIP 18 
VSNS 20 
PJ11 
SHORT NI 
11 2 2
J24 
SHORT NI 
11 2 2
U123 
TPS51200 
REFIN 1
VLDOIN 2
VO 3
PGND 4
VOSNS 5
VIN 10 
PGOOD 9
GND 8
EN 7
REFOUT 6
GND-EP TH 
PC86 
1UF 
X7R 
16V 
C0603 
10% 
C856 
0.1UF 
16V 
C0402 
X7R 
PR32 0
5% R1206 
PR37 10K 
R0402 1% 
PJ12 
SHORT NI 
11 2 2
PC84 
10UF 
X5R 
6.3V 
C0805_H64 
20% 
PC72 
10UF 
X6S 
25V 
C1206_H76 
20% 
PC77 0.1UF 
X7R 16V 
C0402 10% 
PR40 
3.65K 
1% 
R0402 
PC74 
10UF 
X6S 
25V 
C1206_H76 
20% 
R1241 
1K 
1% 
R0402 
NI 
PR103 
19.1K 
1% 
R0402 
PQ2 
FDML7610AS 
3
1
2
D1_EP 
S1/D2_EP 
4
8
5-6-7 
+
PC80 
330UF 
TANT 
2V 
35% 
TAJ_SX 
NI 
1 2
C858 
10UF 
6.3V 
C0805_H64 
X5R 
20% 
Q43 
BSS138LT1G 
G 1
S 2D3
PR31 
4.7K 
R0402 
5% 
C854 
10UF 
6.3V 
C0805_H64 
X5R 
20% 
PC82 
10UF 
X7R 
10V 
C0805_H61 
10% 
NI 
PC81 
10UF 
X7R 
10V 
C0805_H61 
10% 
NI 
PR33 
10K 
1% 
R0402 
NI 
PC71 
1500PF 
X7R 
50V 
C0402 
10% 
PC83 
10UF 
X5R 
6.3V 
C0805_H64 
20% 
PC31 
0.1UF 
X7R 
16V 
C0402 
10% 
C859 
10UF 
6.3V 
C0805_H64 
X5R 
20% 
NI 
C855 
0.1UF 
16V 
C0402 
X7R 
10% 
PJ9 
SHORT 
NI 
1 122
C198 
0.1UF 
X7R 
16V 
10% 
C0402 
PC76 
1UF 
X7R 
16V 
C0603 
10% 
PL7 3.3UH 
21
R1124 
10K 
0.10% 
R0402 
PR34 100 
R0402 1% 
+
PC79 
330UF 
TANT 
2V 
35% 
TAJ_SX 
1 2
R1126 4.7K 
R0402 5% 
R1123 
4.7K 
R0402 
5% 
C853 
1UF 
C0402 
X5R 
6.3V 
10% 
PC78 
0.1UF 
X7R 
16V 
C0402 
10% 
PR36 
10K 
1% 
R0402 
PC73 
10UF 
X6S 
25V 
C1206_H76 
20% 
R1125 
10K 
0.10% 
R0402 
PR35 100 
R0402 1% 
PC85 
4700PF 
X7R 
25V 
C0402 
10% 
PR38 
1.1K 
1% 
R0402 
PJ10 
SHORT NI 
11 2 2
PC75 
0.1UF 
X7R 
16V 
C0402 
10% 
R1242 
1K 
1% 
R0402 
NI 



5
5
4
4
3
3
2
2
1
1
D D
C C
B B
A A
Design specification 
2012.5.7 Modified by <name> 
Output Voltage = 1.1V¡Ó3.5%(DC¡Ó0.5%) 
Output Ripple & Noise < 22mV(¡Ó1%) 
Transient Tolerance = 77mV(¡Ó3.5%) 
TDC = 2.56A 
Max current = 3.2A (bouget 3.118) 
Over-Current Protection(IC Default*1.3) =4.16A 
Current Step = 2A 
Slew Rate = 1A/us 
Work frequency = 400kHZ 
Efficiency > 85% @TDC 
SMD 7 x 7 x 3.0 
DCR=20mohm 
Irms = 8A 
Place next output choke 
Place next output choke 
No used 
VR_PVCCP_NODE1_LGATE1 
VR_PVCCP_NODE1_OCSET 
FM_CPLD_NODE1_PVCCP_EN VR_PVCCP_NODE1_EN 
VSENSE_VCC_CPU_NODE1 
SVID_CPU_NODE1_DAT_R 
ISENSE_PVCCP_NODE1_ISEN1P 
SVID_CPU_NODE1_CLK_R 
VSENSE_VSS_CPU_NODE1 
ISENSE_PVCCP_NODE1_ISEN1N 
VR_PVCCP_NODE1_FB 
VR_PVCCP_NODE1_TEMPMAX 
VR_PVCCP_NODE1_VSEN 
SVID_CPU_NODE1_PVCCP_ALERT_L 
SVID_CPU_NODE1_PVCCP_CLK 
VR_PVCCP_NODE1_VCC 
VR_PVCCP_NODE1_COMP 
VR_PVCCP_NODE1_TONSET 
VR_PVCCP_NODE1_PVCC 
VR_PVCCP_NODE1_TSEN VR_PVCCP_NODE1_TSEN_R 
VR_PVCCP_NODE1_ICCMAX 
VR_PVCCP_NODE1_IBIAS 
VR_PVCCP_NODE1_RGND 
VR_PVCCP_NODE1_ISEN1P_RR 
VR_PVCCP_NODE1_SETINI 
VR_PVCCP_NODE1_TONSET_R 
VR_PVCCP_NODE1_BOOT1 
VR_PVCCP_NODE1_PHASE1 PWRGD_NODE1_PVCCP_PG 
VR_PVCCP_NODE1_ISEN1P_CC 
SW_VR_PVCCP_NODE1_VIN_FLT 
VR_PVCCP_NODE1_FB_RR 
VR_PVCCP_NODE1_FB_RC VR_PVCCP_NODE1_COMP_RC 
H_CPU_NODE1_VR_HOT_L 
VR_PVCCP_NODE1_UGATE1 
SVID_CPU_NODE1_PVCCP_DAT (18) 
H_CPU_NODE1_VR_HOT_L (67) 
PWRGD_NODE1_PVCCP_PG (67) 
VSENSE_VSS_CPU_NODE1 (21) 
VSENSE_VCC_CPU_NODE1 (21) 
SVID_CPU_NODE1_PVCCP_ALERT_L 
FM_CPLD_NODE1_PVCCP_EN (67) 
VR_PVCCP_NODE1_PHASE1 
VR_PVCCP_NODE1_PHASE1 
SVID_CPU_NODE1_PVCCP_CLK (18) 
AGND_PVCCP_NODE1 
AGND_PVCCP_NODE1 
P3V3_NODE1 
AGND_PVCCP_NODE1 
PV_VCCP_NODE1 
P5V_STB_NODE1 
VR_PVCCP_NODE1_VCC 
AGND_PVCCP_NODE1 
AGND_PVCCP_NODE1 
P1V05_NODE1 
VR_PVCCP_NODE1_VCC 
AGND_PVCCP_NODE1 
P12V_AUX 
P5V_STB_NODE1 
VR_PVCCP_NODE1_VCC 
AGND_PVCCP_NODE1 
AGND_PVCCP_NODE1 
PV_VCCP_NODE1 
AGND_PVCCP_NODE1 
AGND_PVCCP_NODE1 
AGND_PVCCP_NODE1 
P3V3_NODE1 
AGND_PVCCP_NODE1 
AGND_PVCCP_NODE1 
P5V_STB_NODE1 
P5V_STB_NODE1 
P3V3_NODE1 
PV_VCCP_NODE1 
Title 
Size Document Number Rev
Date: Sheet 
of
VCCP_CPU 1A
Chassis Manager Assembly V1 
Cloud Server Infrastructure Engineering
Custom 
81 85Monday, January 27, 2014 
Title 
Size Document Number Rev
Date: Sheet 
of
VCCP_CPU 1A
Chassis Manager Assembly V1 
Cloud Server Infrastructure Engineering
Custom 
81 85Monday, January 27, 2014 
Title 
Size Document Number Rev
Date: Sheet 
of
VCCP_CPU 1A
Chassis Manager Assembly V1 
Cloud Server Infrastructure Engineering
Custom 
81 85Monday, January 27, 2014 
PR42 100K 
5% R0402 
PC115 0.1UF 
C0402 X7R 16V 10% 
NI 
RT8167BGQW 
PU8 
LGATEA 36 
PVCC 37 
RGNDA 26 
VDIO 24 
UGATEA 34 
BOOT1 1
ISENAN 29 
ISENAP 30 
TONSETA 31 
BOOTA 33 
EN 32 
LGATE1 38 PHASE1 39 
UGATE1 40 
GND TH 
IBIAS 19 
ICCMAXA 14 
OCSETA 18 
OCSET 16 
ICCMAX 13 
GFXPS2 8
TMPMAX 12 
VCC 9
SETINIA 10 
SETINI 11 
COMP 5
ISEN1P 3
ISEN1N 4
FB 6
TONSET 2
RGND 7
FBA 27 
PHASEA 35 
COMPA 28 
VR_READY 21 
VRA_READY 22 
ALERT 23 
VRHOT 20 
TSENA 17 
VCLK 25 
TSEN 15 
PR78 53.6K 
1% R0402 
PC108 
68PF 
COG 
50V 
C0402 
5% 
NI 
PC125 
22UF 
X5R 
6.3V 
C0805_H61 
20% 
NI 
PR73 316 
1% R0402 
PC87 
2.2UF 
X7R 
10V 
C0603 
10% 
PR64 280K 
R0402 1% 
PC113 
22UF 
X6S 
4V 
C0805_H61 
20% 
PC117 
22UF 
X6S 
4V 
C0805_H61 
20% 
PR68 274K 
1% R0402 
PR61 20K 
R0402 1% 
PC107 
22UF 
X6S 
4V 
C0805_H61 
20% 
PR46 30.1 
1% R0402 
PC98 
0.1UF 
X7R 
25V C0603 
10% 
PC111 
0.1UF C0402 
X7R 
16V 
10% 
NI 
PJ16 
SHORT NI 
11 2 2
PR57 10K 
R0402 1% 
PC109 
1UF C0402 
X5R 
10V 
10% 
NI 
PR72 3.24K 
1% R0402 
PR52 10K 
R0402 1% 
PJ17 SHORT 
NI 
SHORT_R0603 
11 2 2
PR69 10K 
R0402 1% 
PC90 
0.1UF 
X7R 
16V 
C0402 
10% 
PC101 0.1UF 
X7R 16V C0402 10% 
NI 
PC110 470PF 
X7R 50V C0402 10% 
NI 
PR65 5.1K 
1% R0402 
PJ14 SHORT NI 
11 2 2
PR60 15K 
1% R0402 
PR77 10K 
1% R0402 
PC93 
10UF 
X6S 
25V 
C1206_H76 
20% 
PC94 
10UF 
X6S 
25V 
C1206_H76 
20% 
PR43 4.7 
1% R0402 
PC121 
22UF 
X6S 
4V 
C0805_H61 
20% 
PR67 0
5% R0402 
PR50 150 
1% R0402 
tPR75 
10K_T 
R0402XA 
1 2
PR51 
10K 
1% 
R0402 
NI 
PR74 
634 1% 
R0402 
PC88 
2.2UF 
X7R 
10V 
C0603 
10% 
PC96 
0.1UF 
X7R 
16V C0402 
10% 
PC119 
22UF 
X6S 
4V 
C0805_H61 
20% 
U124 
FDMS3664S 
3 5
1
2
D1_EP 
S1/D2_EP 
4
8
6
7
PR59 10K 
1% R0402 
PR44 56 
1% R0402 
PC120 
22UF 
X6S 
4V 
C0805_H61 
20% 
PR76 4.99K 
1% R0402 
+
PC99 
330UF 
TANT 
2V 
35% 
TAJ_SX 
1 2
PC91 
10UF 
X6S 
25V 
C1206_H76 
20% 
PR48 0
5% R0603 
PC114 
22UF 
X6S 
4V 
C0805_H61 
20% 
PR41 
2.2 1% 
R0603 
PC97 
1UF C0402 
X5R 
6.3V 
10% 
PC118 
22UF 
X6S 
4V 
C0805_H61 
20% 
+
PC100 
330UF 
TANT 
2V 
35% 
TAJ_SX 
NI 
1 2
PR70 0
5% R0402 
PC95 0.1UF 
X7R 16V C0402 10% 
PR62 15K 
1% R0402 
PR45 432 
1% R0402 
PR58 1.21K 
1% R0402 
PR63 100 
1% R0402 
PC112 
22UF 
X6S 
4V 
C0805_H61 
20% 
PC106 
22UF 
X6S 
4V 
C0805_H61 
20% 
PR49 0
5% R1206 
PR71 100 
1% R0402 
PJ15 
SHORT NI 
11 2 2
PC89 
1500PF 
X7R 
50V 
C0402 
10% 
PR79 1K 
1% R0402 NI 
PC123 
22UF 
X5R 
6.3V 
C0805_H61 
20% 
NI 
PC116 
22UF 
X6S 
4V 
C0805_H61 
20% PC126 
22UF 
X5R 
6.3V 
C0805_H61 
20% 
NI 
tPR56 
10K_T R0402XA 
1 2
PR53 
10K 1% 
R0402 
NI 
PC105 
22UF 
X6S 
4V 
C0805_H61 
20% 
PC124 
22UF 
X5R 
6.3V 
C0805_H61 
20% 
NI 
PR55 
1.65K 
1% 
R0402 
PC103 
100PF 
NPO 
50V C0402 
5% 
PC122 0.1UF 
X7R 16V C0402 10% 
PR66 0
5% R0402 
PR54 1K 
R0402 1% 
PC102 22PF 
NPO 50V 
C0402 5% 
2.2UH PL8 
2B 1B 
2A 1A 
PC104 
1UF C0402 
X5R 
10V 
10% 
NI 
PC92 
10UF 
X6S 
25V 
C1206_H76 
20% 



5
5
4
4
3
3
2
2
1
1
D D
C C
B B
A A
FOR CPU HEATSINK 
For TPM 
Title 
Size Document Number Rev
Date: Sheet 
of 
Screw & Hole 1A
Chassis Manager Assembly V1 
Cloud Server Infrastructure Engineering
C
82 85Monday, January 27, 2014 
Title 
Size Document Number Rev
Date: Sheet 
of 
Screw & Hole 1A
Chassis Manager Assembly V1 
Cloud Server Infrastructure Engineering
C
82 85Monday, January 27, 2014 
Title 
Size Document Number Rev
Date: Sheet 
of 
Screw & Hole 1A
Chassis Manager Assembly V1 
Cloud Server Infrastructure Engineering
C
82 85Monday, January 27, 2014 
H4 
D3N 
H8 
HOLE_C12D3-6_7B12_OB5XC6N 
H7 
HOLE_C12D3-8_7B12_OB5XC6N 
H10_NUT 
MBT6M006010 
1
H9 
HOLE_C12D3-6_7B12_OB5XC6N 
PCB 
DAT6MTH3AC0 
1
H10_SRW 
MS06050I000 
1
H10 
C7-77D5-41 
H1 
D3N 
H2 
D3N 
H5 
GNDHOLE_8PIN 
H3 
D3N 
H6 
HOLE_C12D3-8_7B12_OB5XC6N 



5
5
4
4
3
3
2
2
1
1
D D
C C
B B
A A
THRU for EA measured reference. 
TOP_85OHM 
IN3_85OHM 
BOT_85OHM 
THRU_85_OHM 
Title 
Size Document Number Rev
Date: Sheet 
of 
Blank 1A
Chassis Manager Assembly V1 
Cloud Server Infrastructure Engineering
C
83 85Monday, January 27, 2014 
Title 
Size Document Number Rev
Date: Sheet 
of 
Blank 1A
Chassis Manager Assembly V1 
Cloud Server Infrastructure Engineering
C
83 85Monday, January 27, 2014 
Title 
Size Document Number Rev
Date: Sheet 
of 
Blank 1A
Chassis Manager Assembly V1 
Cloud Server Infrastructure Engineering
C
83 85Monday, January 27, 2014 
J4 
SET2DIL 
NI 
2
3
1
J25 
SET2DIL 
NI 
2
3
1
J29 
SET2DIL 
NI 
2
3
1
J30 
SET2DIL 
NI 
2
3
1



5
5
4
4
3
3
2
2
1
1
D D
C C
B B
A A
Title 
Size Document Number Rev
Date: Sheet 
of 
Blank 1A
Chassis Manager Assembly V1 
Cloud Server Infrastructure Engineering
C
84 85Monday, January 27, 2014 
Title 
Size Document Number Rev
Date: Sheet 
of 
Blank 1A
Chassis Manager Assembly V1 
Cloud Server Infrastructure Engineering
C
84 85Monday, January 27, 2014 
Title 
Size Document Number Rev
Date: Sheet 
of 
Blank 1A
Chassis Manager Assembly V1 
Cloud Server Infrastructure Engineering
C
84 85Monday, January 27, 2014 



5
5
4
4
3
3
2
2
1
1
D D
C C
B B
A A
Title 
Size Document Number Rev
Date: Sheet 
of 
Blank 1A
Chassis Manager Assembly V1 
Cloud Server Infrastructure Engineering
C
85 85Monday, January 27, 2014 
Title 
Size Document Number Rev
Date: Sheet 
of 
Blank 1A
Chassis Manager Assembly V1 
Cloud Server Infrastructure Engineering
C
85 85Monday, January 27, 2014 
Title 
Size Document Number Rev
Date: Sheet 
of 
Blank 1A
Chassis Manager Assembly V1 
Cloud Server Infrastructure Engineering
C
85 85Monday, January 27, 2014 